(kicad_sch
	(version 20250114)
	(generator "eeschema")
	(generator_version "9.0")
	(paper "A3")
	(title_block
		(title "usb-c-power-adapter")
		(date "2025-06-24")
		(rev "1.1.2")
		(company "Antmicro")
		(comment 1 "www.antmicro.com")
	)
	(rectangle
		(start 335.28 30.48)
		(end 398.78 71.12)
		(stroke
			(width 0)
			(type dash)
		)
		(fill
			(type none)
		)
	)
	(rectangle
		(start 33.02 30.48)
		(end 330.2 142.24)
		(stroke
			(width 0)
			(type dash)
		)
		(fill
			(type none)
		)
	)
	(rectangle
		(start 165.1 147.32)
		(end 231.14 195.58)
		(stroke
			(width 0)
			(type dash)
		)
		(fill
			(type none)
		)
	)
	(rectangle
		(start 33.02 147.32)
		(end 160.02 200.66)
		(stroke
			(width 0)
			(type dash)
		)
		(fill
			(type none)
		)
	)
	(rectangle
		(start 33.02 205.74)
		(end 160.02 259.08)
		(stroke
			(width 0)
			(type dash)
		)
		(fill
			(type none)
		)
	)
	(rectangle
		(start 335.28 76.2)
		(end 398.78 116.84)
		(stroke
			(width 0)
			(type dash)
		)
		(fill
			(type none)
		)
	)
	(text "Note:\nPlace close to\nthe feedback \nresistors"
		(exclude_from_sim no)
		(at 207.01 83.82 0)
		(effects
			(font
				(size 1.27 1.27)
			)
			(justify left bottom)
		)
	)
	(text "Power save mode enabled, \nVDD, VDRVPre-reg on"
		(exclude_from_sim no)
		(at 63.5 129.286 0)
		(effects
			(font
				(size 1.27 1.27)
			)
			(justify left bottom)
		)
	)
	(text "+5V OK"
		(exclude_from_sim no)
		(at 191.77 160.02 0)
		(effects
			(font
				(size 1.27 1.27)
			)
			(justify left bottom)
		)
	)
	(text "R_FB_H = R_FB_L * (V_OUT - V_FB) / V_FB \n10k * (12 - 0.8) / 0.8 = 140k\n"
		(exclude_from_sim no)
		(at 198.12 100.33 0)
		(effects
			(font
				(size 1.27 1.27)
			)
			(justify left bottom)
		)
	)
	(text "0.8V typ"
		(exclude_from_sim no)
		(at 176.53 92.71 0)
		(effects
			(font
				(size 1.27 1.27)
			)
			(justify left bottom)
		)
	)
	(text "+12V OK"
		(exclude_from_sim no)
		(at 173.99 160.02 0)
		(effects
			(font
				(size 1.27 1.27)
			)
			(justify left bottom)
		)
	)
	(text "Buck Converter"
		(exclude_from_sim no)
		(at 139.7 38.1 0)
		(effects
			(font
				(size 3 3)
			)
			(justify left bottom)
			(href "#1")
		)
	)
	(text "SIC477 can be substituted with SIC472.\nIf so, some components need to be populated\nand some removed:\n\n| Designator	| SIC477	| SIC472	|\n| 				|			|			|\n| R6			| populated	| DNP		|\n| R12			| populated	| DNP		|\n| R16			| DNP		| populated	|\n| R7			| DNP		| populated	|\n| R15			| DNP		| populated	|\n| C13			| DNP		| populated	|\n| C12			| DNP		| populated	|\n| C14			| DNP		| populated	|"
		(exclude_from_sim no)
		(at 213.36 138.43 0)
		(effects
			(font
				(size 1.27 1.27)
			)
			(justify left bottom)
		)
	)
	(text "LED Indicators\n"
		(exclude_from_sim no)
		(at 182.88 154.94 0)
		(effects
			(font
				(size 2.54 2.54)
			)
			(justify left bottom)
		)
	)
	(text "5V0 DC/DC Converter"
		(exclude_from_sim no)
		(at 76.2 154.94 0)
		(effects
			(font
				(size 3 3)
			)
			(justify left bottom)
		)
	)
	(text "Pin used only in SIC472"
		(exclude_from_sim no)
		(at 152.4 95.25 0)
		(effects
			(font
				(size 1.27 1.27)
			)
			(justify left bottom)
		)
	)
	(text "3V3 DC/DC Converter"
		(exclude_from_sim no)
		(at 78.74 213.36 0)
		(effects
			(font
				(size 3 3)
			)
			(justify left bottom)
		)
	)
	(text "Assembly wariants:\n- 84W output (default)\n- 36W output (no SIC477 DC/DC converter, \n	direct output from PD source)\n\n| Designator	| 84W 		| 36W 		|\n| 				|			|			|\n| FB1			| populated	| DNP		|\n| FB2			| DNP		| populated	|\n| U2			| populated	| DNP		|\n| L1			| populated	| DNP		|"
		(exclude_from_sim no)
		(at 45.72 55.88 0)
		(effects
			(font
				(size 1.27 1.27)
			)
			(justify left bottom)
		)
	)
	(text "JST Power Connector"
		(exclude_from_sim no)
		(at 345.44 83.82 0)
		(effects
			(font
				(size 2.54 2.54)
			)
			(justify left bottom)
		)
	)
	(text "NanoFit Output Connector"
		(exclude_from_sim no)
		(at 342.9 38.1 0)
		(effects
			(font
				(size 2.54 2.54)
			)
			(justify left bottom)
		)
	)
	(text "Output current: max 7A"
		(exclude_from_sim no)
		(at 219.71 62.23 0)
		(effects
			(font
				(size 1.27 1.27)
			)
			(justify left bottom)
		)
	)
	(text "+3V3 OK"
		(exclude_from_sim no)
		(at 209.55 160.02 0)
		(effects
			(font
				(size 1.27 1.27)
			)
			(justify left bottom)
		)
	)
	(junction
		(at 287.02 77.47)
		(diameter 0)
		(color 0 0 0 0)
	)
	(junction
		(at 295.91 63.5)
		(diameter 0)
		(color 0 0 0 0)
	)
	(junction
		(at 139.7 170.18)
		(diameter 0)
		(color 0 0 0 0)
	)
	(junction
		(at 193.04 73.66)
		(diameter 0)
		(color 0 0 0 0)
	)
	(junction
		(at 269.24 69.85)
		(diameter 0)
		(color 0 0 0 0)
	)
	(junction
		(at 295.91 92.71)
		(diameter 0)
		(color 0 0 0 0)
	)
	(junction
		(at 217.17 73.66)
		(diameter 0)
		(color 0 0 0 0)
	)
	(junction
		(at 278.13 63.5)
		(diameter 0)
		(color 0 0 0 0)
	)
	(junction
		(at 365.76 104.14)
		(diameter 0)
		(color 0 0 0 0)
	)
	(junction
		(at 135.89 228.6)
		(diameter 0)
		(color 0 0 0 0)
	)
	(junction
		(at 278.13 77.47)
		(diameter 0)
		(color 0 0 0 0)
	)
	(junction
		(at 189.23 92.71)
		(diameter 0)
		(color 0 0 0 0)
	)
	(junction
		(at 106.68 73.66)
		(diameter 0)
		(color 0 0 0 0)
	)
	(junction
		(at 278.13 69.85)
		(diameter 0)
		(color 0 0 0 0)
	)
	(junction
		(at 146.05 170.18)
		(diameter 0)
		(color 0 0 0 0)
	)
	(junction
		(at 167.64 81.28)
		(diameter 0)
		(color 0 0 0 0)
	)
	(junction
		(at 365.76 99.06)
		(diameter 0)
		(color 0 0 0 0)
	)
	(junction
		(at 144.78 90.17)
		(diameter 0)
		(color 0 0 0 0)
	)
	(junction
		(at 304.8 63.5)
		(diameter 0)
		(color 0 0 0 0)
	)
	(junction
		(at 175.26 81.28)
		(diameter 0)
		(color 0 0 0 0)
	)
	(junction
		(at 71.12 175.26)
		(diameter 0)
		(color 0 0 0 0)
	)
	(junction
		(at 36.83 67.31)
		(diameter 0)
		(color 0 0 0 0)
	)
	(junction
		(at 287.02 63.5)
		(diameter 0)
		(color 0 0 0 0)
	)
	(junction
		(at 295.91 77.47)
		(diameter 0)
		(color 0 0 0 0)
	)
	(junction
		(at 128.27 170.18)
		(diameter 0)
		(color 0 0 0 0)
	)
	(junction
		(at 60.96 170.18)
		(diameter 0)
		(color 0 0 0 0)
	)
	(junction
		(at 113.03 228.6)
		(diameter 0)
		(color 0 0 0 0)
	)
	(junction
		(at 144.78 105.41)
		(diameter 0)
		(color 0 0 0 0)
	)
	(junction
		(at 269.24 55.88)
		(diameter 0)
		(color 0 0 0 0)
	)
	(junction
		(at 59.69 73.66)
		(diameter 0)
		(color 0 0 0 0)
	)
	(junction
		(at 87.63 73.66)
		(diameter 0)
		(color 0 0 0 0)
	)
	(junction
		(at 128.27 238.76)
		(diameter 0)
		(color 0 0 0 0)
	)
	(junction
		(at 50.8 170.18)
		(diameter 0)
		(color 0 0 0 0)
	)
	(junction
		(at 226.06 73.66)
		(diameter 0)
		(color 0 0 0 0)
	)
	(junction
		(at 369.57 50.8)
		(diameter 0)
		(color 0 0 0 0)
	)
	(junction
		(at 139.7 228.6)
		(diameter 0)
		(color 0 0 0 0)
	)
	(junction
		(at 135.89 170.18)
		(diameter 0)
		(color 0 0 0 0)
	)
	(junction
		(at 114.3 80.01)
		(diameter 0)
		(color 0 0 0 0)
	)
	(junction
		(at 287.02 92.71)
		(diameter 0)
		(color 0 0 0 0)
	)
	(junction
		(at 304.8 77.47)
		(diameter 0)
		(color 0 0 0 0)
	)
	(junction
		(at 234.95 73.66)
		(diameter 0)
		(color 0 0 0 0)
	)
	(junction
		(at 278.13 55.88)
		(diameter 0)
		(color 0 0 0 0)
	)
	(junction
		(at 101.6 104.14)
		(diameter 0)
		(color 0 0 0 0)
	)
	(junction
		(at 128.27 228.6)
		(diameter 0)
		(color 0 0 0 0)
	)
	(junction
		(at 198.12 73.66)
		(diameter 0)
		(color 0 0 0 0)
	)
	(junction
		(at 96.52 73.66)
		(diameter 0)
		(color 0 0 0 0)
	)
	(junction
		(at 71.12 233.68)
		(diameter 0)
		(color 0 0 0 0)
	)
	(junction
		(at 113.03 170.18)
		(diameter 0)
		(color 0 0 0 0)
	)
	(junction
		(at 78.74 73.66)
		(diameter 0)
		(color 0 0 0 0)
	)
	(junction
		(at 69.85 73.66)
		(diameter 0)
		(color 0 0 0 0)
	)
	(junction
		(at 166.37 90.17)
		(diameter 0)
		(color 0 0 0 0)
	)
	(junction
		(at 269.24 85.09)
		(diameter 0)
		(color 0 0 0 0)
	)
	(junction
		(at 278.13 85.09)
		(diameter 0)
		(color 0 0 0 0)
	)
	(junction
		(at 295.91 69.85)
		(diameter 0)
		(color 0 0 0 0)
	)
	(junction
		(at 295.91 55.88)
		(diameter 0)
		(color 0 0 0 0)
	)
	(junction
		(at 49.53 73.66)
		(diameter 0)
		(color 0 0 0 0)
	)
	(junction
		(at 287.02 85.09)
		(diameter 0)
		(color 0 0 0 0)
	)
	(junction
		(at 287.02 69.85)
		(diameter 0)
		(color 0 0 0 0)
	)
	(junction
		(at 128.27 180.34)
		(diameter 0)
		(color 0 0 0 0)
	)
	(junction
		(at 60.96 228.6)
		(diameter 0)
		(color 0 0 0 0)
	)
	(junction
		(at 278.13 92.71)
		(diameter 0)
		(color 0 0 0 0)
	)
	(junction
		(at 361.95 50.8)
		(diameter 0)
		(color 0 0 0 0)
	)
	(junction
		(at 287.02 55.88)
		(diameter 0)
		(color 0 0 0 0)
	)
	(junction
		(at 195.58 73.66)
		(diameter 0)
		(color 0 0 0 0)
	)
	(junction
		(at 50.8 228.6)
		(diameter 0)
		(color 0 0 0 0)
	)
	(junction
		(at 146.05 228.6)
		(diameter 0)
		(color 0 0 0 0)
	)
	(no_connect
		(at 115.57 97.79)
	)
	(no_connect
		(at 143.51 87.63)
	)
	(wire
		(pts
			(xy 295.91 76.2) (xy 295.91 77.47)
		)
		(stroke
			(width 0)
			(type default)
		)
	)
	(wire
		(pts
			(xy 111.76 233.68) (xy 113.03 233.68)
		)
		(stroke
			(width 0)
			(type default)
		)
	)
	(wire
		(pts
			(xy 50.8 170.18) (xy 60.96 170.18)
		)
		(stroke
			(width 0)
			(type default)
		)
	)
	(wire
		(pts
			(xy 287.02 92.71) (xy 278.13 92.71)
		)
		(stroke
			(width 0)
			(type default)
		)
	)
	(wire
		(pts
			(xy 135.89 224.79) (xy 135.89 228.6)
		)
		(stroke
			(width 0)
			(type default)
		)
	)
	(wire
		(pts
			(xy 295.91 69.85) (xy 304.8 69.85)
		)
		(stroke
			(width 0)
			(type default)
		)
	)
	(wire
		(pts
			(xy 104.14 180.34) (xy 104.14 177.8)
		)
		(stroke
			(width 0)
			(type default)
		)
	)
	(wire
		(pts
			(xy 63.5 233.68) (xy 60.96 233.68)
		)
		(stroke
			(width 0)
			(type default)
		)
	)
	(wire
		(pts
			(xy 99.06 106.68) (xy 101.6 106.68)
		)
		(stroke
			(width 0)
			(type default)
		)
	)
	(wire
		(pts
			(xy 128.27 228.6) (xy 135.89 228.6)
		)
		(stroke
			(width 0)
			(type default)
		)
	)
	(wire
		(pts
			(xy 278.13 85.09) (xy 287.02 85.09)
		)
		(stroke
			(width 0)
			(type default)
		)
	)
	(wire
		(pts
			(xy 99.06 115.57) (xy 99.06 116.84)
		)
		(stroke
			(width 0)
			(type default)
		)
	)
	(wire
		(pts
			(xy 146.05 170.18) (xy 153.67 170.18)
		)
		(stroke
			(width 0)
			(type default)
		)
	)
	(wire
		(pts
			(xy 78.74 73.66) (xy 78.74 76.2)
		)
		(stroke
			(width 0)
			(type default)
		)
	)
	(wire
		(pts
			(xy 64.77 113.03) (xy 64.77 116.84)
		)
		(stroke
			(width 0)
			(type default)
		)
	)
	(wire
		(pts
			(xy 106.68 85.09) (xy 115.57 85.09)
		)
		(stroke
			(width 0)
			(type default)
		)
	)
	(wire
		(pts
			(xy 143.51 100.33) (xy 147.32 100.33)
		)
		(stroke
			(width 0)
			(type default)
		)
	)
	(wire
		(pts
			(xy 361.95 50.8) (xy 369.57 50.8)
		)
		(stroke
			(width 0)
			(type default)
		)
	)
	(wire
		(pts
			(xy 60.96 170.18) (xy 86.36 170.18)
		)
		(stroke
			(width 0)
			(type default)
		)
	)
	(wire
		(pts
			(xy 36.83 67.31) (xy 36.83 73.66)
		)
		(stroke
			(width 0)
			(type default)
		)
	)
	(wire
		(pts
			(xy 96.52 73.66) (xy 96.52 76.2)
		)
		(stroke
			(width 0)
			(type default)
		)
	)
	(wire
		(pts
			(xy 49.53 73.66) (xy 59.69 73.66)
		)
		(stroke
			(width 0)
			(type default)
		)
	)
	(wire
		(pts
			(xy 278.13 92.71) (xy 269.24 92.71)
		)
		(stroke
			(width 0)
			(type default)
		)
	)
	(wire
		(pts
			(xy 365.76 104.14) (xy 363.22 104.14)
		)
		(stroke
			(width 0)
			(type default)
		)
	)
	(wire
		(pts
			(xy 144.78 87.63) (xy 144.78 90.17)
		)
		(stroke
			(width 0)
			(type default)
		)
	)
	(wire
		(pts
			(xy 96.52 81.28) (xy 96.52 82.55)
		)
		(stroke
			(width 0)
			(type default)
		)
	)
	(wire
		(pts
			(xy 355.6 50.8) (xy 347.98 50.8)
		)
		(stroke
			(width 0)
			(type default)
		)
	)
	(wire
		(pts
			(xy 101.6 233.68) (xy 106.68 233.68)
		)
		(stroke
			(width 0)
			(type default)
		)
	)
	(wire
		(pts
			(xy 269.24 54.61) (xy 269.24 55.88)
		)
		(stroke
			(width 0)
			(type default)
		)
	)
	(wire
		(pts
			(xy 69.85 73.66) (xy 78.74 73.66)
		)
		(stroke
			(width 0)
			(type default)
		)
	)
	(wire
		(pts
			(xy 193.04 81.28) (xy 193.04 73.66)
		)
		(stroke
			(width 0)
			(type default)
		)
	)
	(wire
		(pts
			(xy 151.13 73.66) (xy 152.4 73.66)
		)
		(stroke
			(width 0)
			(type default)
		)
	)
	(wire
		(pts
			(xy 295.91 69.85) (xy 295.91 71.12)
		)
		(stroke
			(width 0)
			(type default)
		)
	)
	(wire
		(pts
			(xy 128.27 170.18) (xy 135.89 170.18)
		)
		(stroke
			(width 0)
			(type default)
		)
	)
	(wire
		(pts
			(xy 287.02 63.5) (xy 278.13 63.5)
		)
		(stroke
			(width 0)
			(type default)
		)
	)
	(wire
		(pts
			(xy 180.34 73.66) (xy 193.04 73.66)
		)
		(stroke
			(width 0)
			(type default)
		)
	)
	(wire
		(pts
			(xy 44.45 73.66) (xy 49.53 73.66)
		)
		(stroke
			(width 0)
			(type default)
		)
	)
	(wire
		(pts
			(xy 80.01 236.22) (xy 86.36 236.22)
		)
		(stroke
			(width 0)
			(type default)
		)
	)
	(wire
		(pts
			(xy 101.6 228.6) (xy 113.03 228.6)
		)
		(stroke
			(width 0)
			(type default)
		)
	)
	(wire
		(pts
			(xy 363.22 93.98) (xy 365.76 93.98)
		)
		(stroke
			(width 0)
			(type default)
		)
	)
	(wire
		(pts
			(xy 96.52 73.66) (xy 87.63 73.66)
		)
		(stroke
			(width 0)
			(type default)
		)
	)
	(wire
		(pts
			(xy 269.24 86.36) (xy 269.24 85.09)
		)
		(stroke
			(width 0)
			(type default)
		)
	)
	(wire
		(pts
			(xy 135.89 166.37) (xy 135.89 170.18)
		)
		(stroke
			(width 0)
			(type default)
		)
	)
	(wire
		(pts
			(xy 269.24 71.12) (xy 269.24 69.85)
		)
		(stroke
			(width 0)
			(type default)
		)
	)
	(wire
		(pts
			(xy 304.8 55.88) (xy 304.8 57.15)
		)
		(stroke
			(width 0)
			(type default)
		)
	)
	(wire
		(pts
			(xy 50.8 241.3) (xy 50.8 250.19)
		)
		(stroke
			(width 0)
			(type default)
		)
	)
	(wire
		(pts
			(xy 36.83 73.66) (xy 39.37 73.66)
		)
		(stroke
			(width 0)
			(type default)
		)
	)
	(wire
		(pts
			(xy 87.63 81.28) (xy 87.63 82.55)
		)
		(stroke
			(width 0)
			(type default)
		)
	)
	(wire
		(pts
			(xy 139.7 181.61) (xy 139.7 191.77)
		)
		(stroke
			(width 0)
			(type default)
		)
	)
	(wire
		(pts
			(xy 106.68 113.03) (xy 106.68 116.84)
		)
		(stroke
			(width 0)
			(type default)
		)
	)
	(wire
		(pts
			(xy 365.76 93.98) (xy 365.76 99.06)
		)
		(stroke
			(width 0)
			(type default)
		)
	)
	(wire
		(pts
			(xy 62.23 66.04) (xy 62.23 67.31)
		)
		(stroke
			(width 0)
			(type default)
		)
	)
	(wire
		(pts
			(xy 167.64 85.09) (xy 167.64 81.28)
		)
		(stroke
			(width 0)
			(type default)
		)
	)
	(wire
		(pts
			(xy 295.91 91.44) (xy 295.91 92.71)
		)
		(stroke
			(width 0)
			(type default)
		)
	)
	(wire
		(pts
			(xy 269.24 85.09) (xy 278.13 85.09)
		)
		(stroke
			(width 0)
			(type default)
		)
	)
	(wire
		(pts
			(xy 50.8 182.88) (xy 50.8 191.77)
		)
		(stroke
			(width 0)
			(type default)
		)
	)
	(wire
		(pts
			(xy 365.76 104.14) (xy 365.76 107.95)
		)
		(stroke
			(width 0)
			(type default)
		)
	)
	(wire
		(pts
			(xy 78.74 81.28) (xy 78.74 82.55)
		)
		(stroke
			(width 0)
			(type default)
		)
	)
	(wire
		(pts
			(xy 143.51 85.09) (xy 167.64 85.09)
		)
		(stroke
			(width 0)
			(type default)
		)
	)
	(wire
		(pts
			(xy 104.14 238.76) (xy 128.27 238.76)
		)
		(stroke
			(width 0)
			(type default)
		)
	)
	(wire
		(pts
			(xy 139.7 240.03) (xy 139.7 250.19)
		)
		(stroke
			(width 0)
			(type default)
		)
	)
	(wire
		(pts
			(xy 71.12 233.68) (xy 86.36 233.68)
		)
		(stroke
			(width 0)
			(type default)
		)
	)
	(wire
		(pts
			(xy 287.02 77.47) (xy 278.13 77.47)
		)
		(stroke
			(width 0)
			(type default)
		)
	)
	(wire
		(pts
			(xy 360.68 50.8) (xy 361.95 50.8)
		)
		(stroke
			(width 0)
			(type default)
		)
	)
	(wire
		(pts
			(xy 106.68 81.28) (xy 106.68 85.09)
		)
		(stroke
			(width 0)
			(type default)
		)
	)
	(wire
		(pts
			(xy 43.18 167.64) (xy 43.18 170.18)
		)
		(stroke
			(width 0)
			(type default)
		)
	)
	(wire
		(pts
			(xy 113.03 170.18) (xy 118.11 170.18)
		)
		(stroke
			(width 0)
			(type default)
		)
	)
	(wire
		(pts
			(xy 55.88 92.71) (xy 55.88 107.95)
		)
		(stroke
			(width 0)
			(type default)
		)
	)
	(wire
		(pts
			(xy 143.51 90.17) (xy 144.78 90.17)
		)
		(stroke
			(width 0)
			(type default)
		)
	)
	(wire
		(pts
			(xy 295.91 55.88) (xy 295.91 57.15)
		)
		(stroke
			(width 0)
			(type default)
		)
	)
	(wire
		(pts
			(xy 49.53 73.66) (xy 49.53 76.2)
		)
		(stroke
			(width 0)
			(type default)
		)
	)
	(wire
		(pts
			(xy 173.99 81.28) (xy 175.26 81.28)
		)
		(stroke
			(width 0)
			(type default)
		)
	)
	(wire
		(pts
			(xy 374.65 101.6) (xy 374.65 93.98)
		)
		(stroke
			(width 0)
			(type default)
		)
	)
	(wire
		(pts
			(xy 144.78 80.01) (xy 143.51 80.01)
		)
		(stroke
			(width 0)
			(type default)
		)
	)
	(wire
		(pts
			(xy 60.96 175.26) (xy 60.96 170.18)
		)
		(stroke
			(width 0)
			(type default)
		)
	)
	(wire
		(pts
			(xy 71.12 186.69) (xy 71.12 191.77)
		)
		(stroke
			(width 0)
			(type default)
		)
	)
	(wire
		(pts
			(xy 113.03 170.18) (xy 113.03 175.26)
		)
		(stroke
			(width 0)
			(type default)
		)
	)
	(wire
		(pts
			(xy 278.13 62.23) (xy 278.13 63.5)
		)
		(stroke
			(width 0)
			(type default)
		)
	)
	(wire
		(pts
			(xy 46.99 90.17) (xy 46.99 107.95)
		)
		(stroke
			(width 0)
			(type default)
		)
	)
	(wire
		(pts
			(xy 80.01 177.8) (xy 86.36 177.8)
		)
		(stroke
			(width 0)
			(type default)
		)
	)
	(wire
		(pts
			(xy 123.19 228.6) (xy 128.27 228.6)
		)
		(stroke
			(width 0)
			(type default)
		)
	)
	(wire
		(pts
			(xy 139.7 170.18) (xy 146.05 170.18)
		)
		(stroke
			(width 0)
			(type default)
		)
	)
	(wire
		(pts
			(xy 96.52 73.66) (xy 106.68 73.66)
		)
		(stroke
			(width 0)
			(type default)
		)
	)
	(wire
		(pts
			(xy 71.12 245.11) (xy 71.12 250.19)
		)
		(stroke
			(width 0)
			(type default)
		)
	)
	(wire
		(pts
			(xy 287.02 85.09) (xy 287.02 86.36)
		)
		(stroke
			(width 0)
			(type default)
		)
	)
	(wire
		(pts
			(xy 177.8 95.25) (xy 177.8 96.52)
		)
		(stroke
			(width 0)
			(type default)
		)
	)
	(wire
		(pts
			(xy 68.58 175.26) (xy 71.12 175.26)
		)
		(stroke
			(width 0)
			(type default)
		)
	)
	(wire
		(pts
			(xy 59.69 81.28) (xy 59.69 82.55)
		)
		(stroke
			(width 0)
			(type default)
		)
	)
	(wire
		(pts
			(xy 287.02 62.23) (xy 287.02 63.5)
		)
		(stroke
			(width 0)
			(type default)
		)
	)
	(wire
		(pts
			(xy 160.02 73.66) (xy 157.48 73.66)
		)
		(stroke
			(width 0)
			(type default)
		)
	)
	(wire
		(pts
			(xy 59.69 73.66) (xy 69.85 73.66)
		)
		(stroke
			(width 0)
			(type default)
		)
	)
	(wire
		(pts
			(xy 278.13 55.88) (xy 278.13 57.15)
		)
		(stroke
			(width 0)
			(type default)
		)
	)
	(wire
		(pts
			(xy 195.58 73.66) (xy 195.58 86.36)
		)
		(stroke
			(width 0)
			(type default)
		)
	)
	(wire
		(pts
			(xy 195.58 91.44) (xy 195.58 92.71)
		)
		(stroke
			(width 0)
			(type default)
		)
	)
	(wire
		(pts
			(xy 295.91 77.47) (xy 287.02 77.47)
		)
		(stroke
			(width 0)
			(type default)
		)
	)
	(wire
		(pts
			(xy 295.91 55.88) (xy 304.8 55.88)
		)
		(stroke
			(width 0)
			(type default)
		)
	)
	(wire
		(pts
			(xy 146.05 167.64) (xy 146.05 170.18)
		)
		(stroke
			(width 0)
			(type default)
		)
	)
	(wire
		(pts
			(xy 278.13 85.09) (xy 278.13 86.36)
		)
		(stroke
			(width 0)
			(type default)
		)
	)
	(wire
		(pts
			(xy 369.57 54.61) (xy 369.57 50.8)
		)
		(stroke
			(width 0)
			(type default)
		)
	)
	(wire
		(pts
			(xy 143.51 82.55) (xy 160.02 82.55)
		)
		(stroke
			(width 0)
			(type default)
		)
	)
	(wire
		(pts
			(xy 101.6 102.87) (xy 101.6 104.14)
		)
		(stroke
			(width 0)
			(type default)
		)
	)
	(wire
		(pts
			(xy 43.18 228.6) (xy 50.8 228.6)
		)
		(stroke
			(width 0)
			(type default)
		)
	)
	(wire
		(pts
			(xy 278.13 69.85) (xy 287.02 69.85)
		)
		(stroke
			(width 0)
			(type default)
		)
	)
	(wire
		(pts
			(xy 152.4 100.33) (xy 172.72 100.33)
		)
		(stroke
			(width 0)
			(type default)
		)
	)
	(wire
		(pts
			(xy 60.96 228.6) (xy 86.36 228.6)
		)
		(stroke
			(width 0)
			(type default)
		)
	)
	(wire
		(pts
			(xy 278.13 55.88) (xy 287.02 55.88)
		)
		(stroke
			(width 0)
			(type default)
		)
	)
	(wire
		(pts
			(xy 269.24 69.85) (xy 278.13 69.85)
		)
		(stroke
			(width 0)
			(type default)
		)
	)
	(wire
		(pts
			(xy 278.13 91.44) (xy 278.13 92.71)
		)
		(stroke
			(width 0)
			(type default)
		)
	)
	(wire
		(pts
			(xy 50.8 177.8) (xy 50.8 170.18)
		)
		(stroke
			(width 0)
			(type default)
		)
	)
	(wire
		(pts
			(xy 175.26 81.28) (xy 175.26 83.82)
		)
		(stroke
			(width 0)
			(type default)
		)
	)
	(wire
		(pts
			(xy 71.12 233.68) (xy 71.12 240.03)
		)
		(stroke
			(width 0)
			(type default)
		)
	)
	(wire
		(pts
			(xy 198.12 73.66) (xy 217.17 73.66)
		)
		(stroke
			(width 0)
			(type default)
		)
	)
	(wire
		(pts
			(xy 139.7 176.53) (xy 139.7 170.18)
		)
		(stroke
			(width 0)
			(type default)
		)
	)
	(wire
		(pts
			(xy 128.27 241.3) (xy 128.27 238.76)
		)
		(stroke
			(width 0)
			(type default)
		)
	)
	(wire
		(pts
			(xy 153.67 228.6) (xy 153.67 224.79)
		)
		(stroke
			(width 0)
			(type default)
		)
	)
	(wire
		(pts
			(xy 226.06 73.66) (xy 234.95 73.66)
		)
		(stroke
			(width 0)
			(type default)
		)
	)
	(wire
		(pts
			(xy 189.23 101.6) (xy 189.23 116.84)
		)
		(stroke
			(width 0)
			(type default)
		)
	)
	(wire
		(pts
			(xy 295.91 62.23) (xy 295.91 63.5)
		)
		(stroke
			(width 0)
			(type default)
		)
	)
	(wire
		(pts
			(xy 363.22 101.6) (xy 374.65 101.6)
		)
		(stroke
			(width 0)
			(type default)
		)
	)
	(wire
		(pts
			(xy 295.91 93.98) (xy 295.91 92.71)
		)
		(stroke
			(width 0)
			(type default)
		)
	)
	(wire
		(pts
			(xy 195.58 175.26) (xy 195.58 179.07)
		)
		(stroke
			(width 0)
			(type default)
		)
	)
	(wire
		(pts
			(xy 111.76 175.26) (xy 113.03 175.26)
		)
		(stroke
			(width 0)
			(type default)
		)
	)
	(wire
		(pts
			(xy 128.27 182.88) (xy 128.27 180.34)
		)
		(stroke
			(width 0)
			(type default)
		)
	)
	(wire
		(pts
			(xy 104.14 180.34) (xy 128.27 180.34)
		)
		(stroke
			(width 0)
			(type default)
		)
	)
	(wire
		(pts
			(xy 106.68 73.66) (xy 106.68 76.2)
		)
		(stroke
			(width 0)
			(type default)
		)
	)
	(wire
		(pts
			(xy 217.17 73.66) (xy 226.06 73.66)
		)
		(stroke
			(width 0)
			(type default)
		)
	)
	(wire
		(pts
			(xy 295.91 63.5) (xy 287.02 63.5)
		)
		(stroke
			(width 0)
			(type default)
		)
	)
	(wire
		(pts
			(xy 128.27 246.38) (xy 128.27 250.19)
		)
		(stroke
			(width 0)
			(type default)
		)
	)
	(wire
		(pts
			(xy 64.77 95.25) (xy 64.77 107.95)
		)
		(stroke
			(width 0)
			(type default)
		)
	)
	(wire
		(pts
			(xy 144.78 105.41) (xy 144.78 116.84)
		)
		(stroke
			(width 0)
			(type default)
		)
	)
	(wire
		(pts
			(xy 234.95 73.66) (xy 240.03 73.66)
		)
		(stroke
			(width 0)
			(type default)
		)
	)
	(wire
		(pts
			(xy 287.02 91.44) (xy 287.02 92.71)
		)
		(stroke
			(width 0)
			(type default)
		)
	)
	(wire
		(pts
			(xy 363.22 96.52) (xy 368.3 96.52)
		)
		(stroke
			(width 0)
			(type default)
		)
	)
	(wire
		(pts
			(xy 234.95 71.12) (xy 234.95 73.66)
		)
		(stroke
			(width 0)
			(type default)
		)
	)
	(wire
		(pts
			(xy 113.03 228.6) (xy 113.03 233.68)
		)
		(stroke
			(width 0)
			(type default)
		)
	)
	(wire
		(pts
			(xy 80.01 177.8) (xy 80.01 191.77)
		)
		(stroke
			(width 0)
			(type default)
		)
	)
	(wire
		(pts
			(xy 99.06 106.68) (xy 99.06 110.49)
		)
		(stroke
			(width 0)
			(type default)
		)
	)
	(wire
		(pts
			(xy 114.3 80.01) (xy 115.57 80.01)
		)
		(stroke
			(width 0)
			(type default)
		)
	)
	(wire
		(pts
			(xy 114.3 80.01) (xy 114.3 73.66)
		)
		(stroke
			(width 0)
			(type default)
		)
	)
	(wire
		(pts
			(xy 287.02 69.85) (xy 295.91 69.85)
		)
		(stroke
			(width 0)
			(type default)
		)
	)
	(wire
		(pts
			(xy 128.27 170.18) (xy 128.27 172.72)
		)
		(stroke
			(width 0)
			(type default)
		)
	)
	(wire
		(pts
			(xy 278.13 69.85) (xy 278.13 71.12)
		)
		(stroke
			(width 0)
			(type default)
		)
	)
	(wire
		(pts
			(xy 269.24 55.88) (xy 278.13 55.88)
		)
		(stroke
			(width 0)
			(type default)
		)
	)
	(wire
		(pts
			(xy 69.85 81.28) (xy 69.85 82.55)
		)
		(stroke
			(width 0)
			(type default)
		)
	)
	(wire
		(pts
			(xy 382.27 102.87) (xy 382.27 101.6)
		)
		(stroke
			(width 0)
			(type default)
		)
	)
	(wire
		(pts
			(xy 104.14 236.22) (xy 104.14 238.76)
		)
		(stroke
			(width 0)
			(type default)
		)
	)
	(wire
		(pts
			(xy 143.51 92.71) (xy 189.23 92.71)
		)
		(stroke
			(width 0)
			(type default)
		)
	)
	(wire
		(pts
			(xy 139.7 234.95) (xy 139.7 228.6)
		)
		(stroke
			(width 0)
			(type default)
		)
	)
	(wire
		(pts
			(xy 304.8 76.2) (xy 304.8 77.47)
		)
		(stroke
			(width 0)
			(type default)
		)
	)
	(wire
		(pts
			(xy 213.36 175.26) (xy 213.36 179.07)
		)
		(stroke
			(width 0)
			(type default)
		)
	)
	(wire
		(pts
			(xy 213.36 167.64) (xy 213.36 170.18)
		)
		(stroke
			(width 0)
			(type default)
		)
	)
	(wire
		(pts
			(xy 114.3 82.55) (xy 114.3 80.01)
		)
		(stroke
			(width 0)
			(type default)
		)
	)
	(wire
		(pts
			(xy 177.8 107.95) (xy 177.8 116.84)
		)
		(stroke
			(width 0)
			(type default)
		)
	)
	(wire
		(pts
			(xy 167.64 81.28) (xy 167.64 73.66)
		)
		(stroke
			(width 0)
			(type default)
		)
	)
	(wire
		(pts
			(xy 146.05 226.06) (xy 146.05 228.6)
		)
		(stroke
			(width 0)
			(type default)
		)
	)
	(wire
		(pts
			(xy 63.5 175.26) (xy 60.96 175.26)
		)
		(stroke
			(width 0)
			(type default)
		)
	)
	(wire
		(pts
			(xy 304.8 63.5) (xy 295.91 63.5)
		)
		(stroke
			(width 0)
			(type default)
		)
	)
	(wire
		(pts
			(xy 43.18 226.06) (xy 43.18 228.6)
		)
		(stroke
			(width 0)
			(type default)
		)
	)
	(wire
		(pts
			(xy 195.58 167.64) (xy 195.58 170.18)
		)
		(stroke
			(width 0)
			(type default)
		)
	)
	(wire
		(pts
			(xy 123.19 170.18) (xy 128.27 170.18)
		)
		(stroke
			(width 0)
			(type default)
		)
	)
	(wire
		(pts
			(xy 195.58 92.71) (xy 189.23 92.71)
		)
		(stroke
			(width 0)
			(type default)
		)
	)
	(wire
		(pts
			(xy 195.58 184.15) (xy 195.58 186.69)
		)
		(stroke
			(width 0)
			(type default)
		)
	)
	(wire
		(pts
			(xy 240.03 73.66) (xy 240.03 74.93)
		)
		(stroke
			(width 0)
			(type default)
		)
	)
	(wire
		(pts
			(xy 240.03 80.01) (xy 240.03 81.28)
		)
		(stroke
			(width 0)
			(type default)
		)
	)
	(wire
		(pts
			(xy 377.19 53.34) (xy 377.19 63.5)
		)
		(stroke
			(width 0)
			(type default)
		)
	)
	(wire
		(pts
			(xy 71.12 175.26) (xy 71.12 181.61)
		)
		(stroke
			(width 0)
			(type default)
		)
	)
	(wire
		(pts
			(xy 144.78 73.66) (xy 146.05 73.66)
		)
		(stroke
			(width 0)
			(type default)
		)
	)
	(wire
		(pts
			(xy 139.7 228.6) (xy 146.05 228.6)
		)
		(stroke
			(width 0)
			(type default)
		)
	)
	(wire
		(pts
			(xy 361.95 50.8) (xy 361.95 55.88)
		)
		(stroke
			(width 0)
			(type default)
		)
	)
	(wire
		(pts
			(xy 128.27 180.34) (xy 128.27 177.8)
		)
		(stroke
			(width 0)
			(type default)
		)
	)
	(wire
		(pts
			(xy 278.13 63.5) (xy 269.24 63.5)
		)
		(stroke
			(width 0)
			(type default)
		)
	)
	(wire
		(pts
			(xy 106.68 73.66) (xy 114.3 73.66)
		)
		(stroke
			(width 0)
			(type default)
		)
	)
	(wire
		(pts
			(xy 100.33 104.14) (xy 101.6 104.14)
		)
		(stroke
			(width 0)
			(type default)
		)
	)
	(wire
		(pts
			(xy 198.12 80.01) (xy 198.12 81.28)
		)
		(stroke
			(width 0)
			(type default)
		)
	)
	(wire
		(pts
			(xy 190.5 81.28) (xy 193.04 81.28)
		)
		(stroke
			(width 0)
			(type default)
		)
	)
	(wire
		(pts
			(xy 46.99 90.17) (xy 115.57 90.17)
		)
		(stroke
			(width 0)
			(type default)
		)
	)
	(wire
		(pts
			(xy 365.76 99.06) (xy 365.76 104.14)
		)
		(stroke
			(width 0)
			(type default)
		)
	)
	(wire
		(pts
			(xy 391.16 102.87) (xy 391.16 101.6)
		)
		(stroke
			(width 0)
			(type default)
		)
	)
	(wire
		(pts
			(xy 369.57 50.8) (xy 378.46 50.8)
		)
		(stroke
			(width 0)
			(type default)
		)
	)
	(wire
		(pts
			(xy 113.03 228.6) (xy 118.11 228.6)
		)
		(stroke
			(width 0)
			(type default)
		)
	)
	(wire
		(pts
			(xy 115.57 82.55) (xy 114.3 82.55)
		)
		(stroke
			(width 0)
			(type default)
		)
	)
	(wire
		(pts
			(xy 377.19 53.34) (xy 378.46 53.34)
		)
		(stroke
			(width 0)
			(type default)
		)
	)
	(wire
		(pts
			(xy 143.51 105.41) (xy 144.78 105.41)
		)
		(stroke
			(width 0)
			(type default)
		)
	)
	(wire
		(pts
			(xy 144.78 73.66) (xy 144.78 80.01)
		)
		(stroke
			(width 0)
			(type default)
		)
	)
	(wire
		(pts
			(xy 36.83 67.31) (xy 39.37 67.31)
		)
		(stroke
			(width 0)
			(type default)
		)
	)
	(wire
		(pts
			(xy 304.8 69.85) (xy 304.8 71.12)
		)
		(stroke
			(width 0)
			(type default)
		)
	)
	(wire
		(pts
			(xy 213.36 184.15) (xy 213.36 186.69)
		)
		(stroke
			(width 0)
			(type default)
		)
	)
	(wire
		(pts
			(xy 69.85 73.66) (xy 69.85 76.2)
		)
		(stroke
			(width 0)
			(type default)
		)
	)
	(wire
		(pts
			(xy 101.6 106.68) (xy 101.6 104.14)
		)
		(stroke
			(width 0)
			(type default)
		)
	)
	(wire
		(pts
			(xy 287.02 85.09) (xy 295.91 85.09)
		)
		(stroke
			(width 0)
			(type default)
		)
	)
	(wire
		(pts
			(xy 143.51 95.25) (xy 177.8 95.25)
		)
		(stroke
			(width 0)
			(type default)
		)
	)
	(wire
		(pts
			(xy 106.68 105.41) (xy 106.68 107.95)
		)
		(stroke
			(width 0)
			(type default)
		)
	)
	(wire
		(pts
			(xy 68.58 233.68) (xy 71.12 233.68)
		)
		(stroke
			(width 0)
			(type default)
		)
	)
	(wire
		(pts
			(xy 72.39 113.03) (xy 72.39 116.84)
		)
		(stroke
			(width 0)
			(type default)
		)
	)
	(wire
		(pts
			(xy 101.6 175.26) (xy 106.68 175.26)
		)
		(stroke
			(width 0)
			(type default)
		)
	)
	(wire
		(pts
			(xy 154.94 87.63) (xy 163.83 87.63)
		)
		(stroke
			(width 0)
			(type default)
		)
	)
	(wire
		(pts
			(xy 295.91 92.71) (xy 287.02 92.71)
		)
		(stroke
			(width 0)
			(type default)
		)
	)
	(wire
		(pts
			(xy 177.8 101.6) (xy 177.8 102.87)
		)
		(stroke
			(width 0)
			(type default)
		)
	)
	(wire
		(pts
			(xy 168.91 81.28) (xy 167.64 81.28)
		)
		(stroke
			(width 0)
			(type default)
		)
	)
	(wire
		(pts
			(xy 189.23 92.71) (xy 189.23 96.52)
		)
		(stroke
			(width 0)
			(type default)
		)
	)
	(wire
		(pts
			(xy 78.74 73.66) (xy 87.63 73.66)
		)
		(stroke
			(width 0)
			(type default)
		)
	)
	(wire
		(pts
			(xy 269.24 63.5) (xy 269.24 62.23)
		)
		(stroke
			(width 0)
			(type default)
		)
	)
	(wire
		(pts
			(xy 128.27 238.76) (xy 128.27 236.22)
		)
		(stroke
			(width 0)
			(type default)
		)
	)
	(wire
		(pts
			(xy 80.01 104.14) (xy 95.25 104.14)
		)
		(stroke
			(width 0)
			(type default)
		)
	)
	(wire
		(pts
			(xy 101.6 236.22) (xy 104.14 236.22)
		)
		(stroke
			(width 0)
			(type default)
		)
	)
	(wire
		(pts
			(xy 369.57 63.5) (xy 369.57 59.69)
		)
		(stroke
			(width 0)
			(type default)
		)
	)
	(wire
		(pts
			(xy 177.8 184.15) (xy 177.8 186.69)
		)
		(stroke
			(width 0)
			(type default)
		)
	)
	(wire
		(pts
			(xy 115.57 105.41) (xy 106.68 105.41)
		)
		(stroke
			(width 0)
			(type default)
		)
	)
	(wire
		(pts
			(xy 135.89 228.6) (xy 139.7 228.6)
		)
		(stroke
			(width 0)
			(type default)
		)
	)
	(wire
		(pts
			(xy 295.91 85.09) (xy 295.91 86.36)
		)
		(stroke
			(width 0)
			(type default)
		)
	)
	(wire
		(pts
			(xy 71.12 175.26) (xy 86.36 175.26)
		)
		(stroke
			(width 0)
			(type default)
		)
	)
	(wire
		(pts
			(xy 175.26 90.17) (xy 175.26 88.9)
		)
		(stroke
			(width 0)
			(type default)
		)
	)
	(wire
		(pts
			(xy 166.37 90.17) (xy 175.26 90.17)
		)
		(stroke
			(width 0)
			(type default)
		)
	)
	(wire
		(pts
			(xy 43.18 170.18) (xy 50.8 170.18)
		)
		(stroke
			(width 0)
			(type default)
		)
	)
	(wire
		(pts
			(xy 269.24 68.58) (xy 269.24 69.85)
		)
		(stroke
			(width 0)
			(type default)
		)
	)
	(wire
		(pts
			(xy 80.01 236.22) (xy 80.01 250.19)
		)
		(stroke
			(width 0)
			(type default)
		)
	)
	(wire
		(pts
			(xy 269.24 57.15) (xy 269.24 55.88)
		)
		(stroke
			(width 0)
			(type default)
		)
	)
	(wire
		(pts
			(xy 287.02 69.85) (xy 287.02 71.12)
		)
		(stroke
			(width 0)
			(type default)
		)
	)
	(wire
		(pts
			(xy 128.27 228.6) (xy 128.27 231.14)
		)
		(stroke
			(width 0)
			(type default)
		)
	)
	(wire
		(pts
			(xy 60.96 233.68) (xy 60.96 228.6)
		)
		(stroke
			(width 0)
			(type default)
		)
	)
	(wire
		(pts
			(xy 36.83 55.88) (xy 36.83 67.31)
		)
		(stroke
			(width 0)
			(type default)
		)
	)
	(wire
		(pts
			(xy 269.24 77.47) (xy 269.24 76.2)
		)
		(stroke
			(width 0)
			(type default)
		)
	)
	(wire
		(pts
			(xy 368.3 93.98) (xy 368.3 96.52)
		)
		(stroke
			(width 0)
			(type default)
		)
	)
	(wire
		(pts
			(xy 304.8 62.23) (xy 304.8 63.5)
		)
		(stroke
			(width 0)
			(type default)
		)
	)
	(wire
		(pts
			(xy 44.45 67.31) (xy 62.23 67.31)
		)
		(stroke
			(width 0)
			(type default)
		)
	)
	(wire
		(pts
			(xy 287.02 55.88) (xy 295.91 55.88)
		)
		(stroke
			(width 0)
			(type default)
		)
	)
	(wire
		(pts
			(xy 87.63 73.66) (xy 87.63 76.2)
		)
		(stroke
			(width 0)
			(type default)
		)
	)
	(wire
		(pts
			(xy 49.53 81.28) (xy 49.53 82.55)
		)
		(stroke
			(width 0)
			(type default)
		)
	)
	(wire
		(pts
			(xy 72.39 100.33) (xy 72.39 107.95)
		)
		(stroke
			(width 0)
			(type default)
		)
	)
	(wire
		(pts
			(xy 175.26 81.28) (xy 185.42 81.28)
		)
		(stroke
			(width 0)
			(type default)
		)
	)
	(wire
		(pts
			(xy 64.77 95.25) (xy 115.57 95.25)
		)
		(stroke
			(width 0)
			(type default)
		)
	)
	(wire
		(pts
			(xy 347.98 50.8) (xy 347.98 48.26)
		)
		(stroke
			(width 0)
			(type default)
		)
	)
	(wire
		(pts
			(xy 198.12 73.66) (xy 198.12 74.93)
		)
		(stroke
			(width 0)
			(type default)
		)
	)
	(wire
		(pts
			(xy 382.27 95.25) (xy 382.27 96.52)
		)
		(stroke
			(width 0)
			(type default)
		)
	)
	(wire
		(pts
			(xy 226.06 71.12) (xy 226.06 73.66)
		)
		(stroke
			(width 0)
			(type default)
		)
	)
	(wire
		(pts
			(xy 144.78 90.17) (xy 166.37 90.17)
		)
		(stroke
			(width 0)
			(type default)
		)
	)
	(wire
		(pts
			(xy 391.16 95.25) (xy 391.16 96.52)
		)
		(stroke
			(width 0)
			(type default)
		)
	)
	(wire
		(pts
			(xy 104.14 177.8) (xy 101.6 177.8)
		)
		(stroke
			(width 0)
			(type default)
		)
	)
	(wire
		(pts
			(xy 278.13 76.2) (xy 278.13 77.47)
		)
		(stroke
			(width 0)
			(type default)
		)
	)
	(wire
		(pts
			(xy 177.8 175.26) (xy 177.8 179.07)
		)
		(stroke
			(width 0)
			(type default)
		)
	)
	(wire
		(pts
			(xy 304.8 78.74) (xy 304.8 77.47)
		)
		(stroke
			(width 0)
			(type default)
		)
	)
	(wire
		(pts
			(xy 128.27 187.96) (xy 128.27 191.77)
		)
		(stroke
			(width 0)
			(type default)
		)
	)
	(wire
		(pts
			(xy 363.22 99.06) (xy 365.76 99.06)
		)
		(stroke
			(width 0)
			(type default)
		)
	)
	(wire
		(pts
			(xy 101.6 170.18) (xy 113.03 170.18)
		)
		(stroke
			(width 0)
			(type default)
		)
	)
	(wire
		(pts
			(xy 304.8 64.77) (xy 304.8 63.5)
		)
		(stroke
			(width 0)
			(type default)
		)
	)
	(wire
		(pts
			(xy 287.02 76.2) (xy 287.02 77.47)
		)
		(stroke
			(width 0)
			(type default)
		)
	)
	(wire
		(pts
			(xy 50.8 236.22) (xy 50.8 228.6)
		)
		(stroke
			(width 0)
			(type default)
		)
	)
	(wire
		(pts
			(xy 269.24 83.82) (xy 269.24 85.09)
		)
		(stroke
			(width 0)
			(type default)
		)
	)
	(wire
		(pts
			(xy 160.02 82.55) (xy 160.02 73.66)
		)
		(stroke
			(width 0)
			(type default)
		)
	)
	(wire
		(pts
			(xy 195.58 73.66) (xy 198.12 73.66)
		)
		(stroke
			(width 0)
			(type default)
		)
	)
	(wire
		(pts
			(xy 72.39 100.33) (xy 115.57 100.33)
		)
		(stroke
			(width 0)
			(type default)
		)
	)
	(wire
		(pts
			(xy 287.02 55.88) (xy 287.02 57.15)
		)
		(stroke
			(width 0)
			(type default)
		)
	)
	(wire
		(pts
			(xy 177.8 167.64) (xy 177.8 170.18)
		)
		(stroke
			(width 0)
			(type default)
		)
	)
	(wire
		(pts
			(xy 144.78 102.87) (xy 144.78 105.41)
		)
		(stroke
			(width 0)
			(type default)
		)
	)
	(wire
		(pts
			(xy 153.67 170.18) (xy 153.67 166.37)
		)
		(stroke
			(width 0)
			(type default)
		)
	)
	(wire
		(pts
			(xy 193.04 73.66) (xy 195.58 73.66)
		)
		(stroke
			(width 0)
			(type default)
		)
	)
	(wire
		(pts
			(xy 149.86 87.63) (xy 144.78 87.63)
		)
		(stroke
			(width 0)
			(type default)
		)
	)
	(wire
		(pts
			(xy 361.95 60.96) (xy 361.95 63.5)
		)
		(stroke
			(width 0)
			(type default)
		)
	)
	(wire
		(pts
			(xy 144.78 102.87) (xy 143.51 102.87)
		)
		(stroke
			(width 0)
			(type default)
		)
	)
	(wire
		(pts
			(xy 101.6 102.87) (xy 115.57 102.87)
		)
		(stroke
			(width 0)
			(type default)
		)
	)
	(wire
		(pts
			(xy 269.24 92.71) (xy 269.24 91.44)
		)
		(stroke
			(width 0)
			(type default)
		)
	)
	(wire
		(pts
			(xy 46.99 113.03) (xy 46.99 116.84)
		)
		(stroke
			(width 0)
			(type default)
		)
	)
	(wire
		(pts
			(xy 55.88 113.03) (xy 55.88 116.84)
		)
		(stroke
			(width 0)
			(type default)
		)
	)
	(wire
		(pts
			(xy 217.17 72.39) (xy 217.17 73.66)
		)
		(stroke
			(width 0)
			(type default)
		)
	)
	(wire
		(pts
			(xy 59.69 73.66) (xy 59.69 76.2)
		)
		(stroke
			(width 0)
			(type default)
		)
	)
	(wire
		(pts
			(xy 163.83 82.55) (xy 163.83 87.63)
		)
		(stroke
			(width 0)
			(type default)
		)
	)
	(wire
		(pts
			(xy 278.13 77.47) (xy 269.24 77.47)
		)
		(stroke
			(width 0)
			(type default)
		)
	)
	(wire
		(pts
			(xy 55.88 92.71) (xy 115.57 92.71)
		)
		(stroke
			(width 0)
			(type default)
		)
	)
	(wire
		(pts
			(xy 135.89 170.18) (xy 139.7 170.18)
		)
		(stroke
			(width 0)
			(type default)
		)
	)
	(wire
		(pts
			(xy 167.64 73.66) (xy 175.26 73.66)
		)
		(stroke
			(width 0)
			(type default)
		)
	)
	(wire
		(pts
			(xy 304.8 77.47) (xy 295.91 77.47)
		)
		(stroke
			(width 0)
			(type default)
		)
	)
	(wire
		(pts
			(xy 50.8 228.6) (xy 60.96 228.6)
		)
		(stroke
			(width 0)
			(type default)
		)
	)
	(wire
		(pts
			(xy 146.05 228.6) (xy 153.67 228.6)
		)
		(stroke
			(width 0)
			(type default)
		)
	)
	(label "12V_SNS"
		(at 176.53 81.28 0)
		(effects
			(font
				(size 1.27 1.27)
			)
			(justify left bottom)
		)
	)
	(label "VDRV_12V_DCDC"
		(at 99.06 92.71 0)
		(effects
			(font
				(size 1.27 1.27)
			)
			(justify left bottom)
		)
	)
	(label "VDD_12V_DCDC"
		(at 99.06 90.17 0)
		(effects
			(font
				(size 1.27 1.27)
			)
			(justify left bottom)
		)
	)
	(label "12V_SS"
		(at 106.68 100.33 0)
		(effects
			(font
				(size 1.27 1.27)
			)
			(justify left bottom)
		)
	)
	(label "12V_FSW"
		(at 106.68 105.41 0)
		(effects
			(font
				(size 1.27 1.27)
			)
			(justify left bottom)
		)
	)
	(label "VDD_12V_DCDC"
		(at 80.01 104.14 0)
		(effects
			(font
				(size 1.27 1.27)
			)
			(justify left bottom)
		)
	)
	(label "VDD_12V_DCDC"
		(at 172.72 100.33 180)
		(effects
			(font
				(size 1.27 1.27)
			)
			(justify right bottom)
		)
	)
	(label "12V_ILIM"
		(at 106.68 102.87 0)
		(effects
			(font
				(size 1.27 1.27)
			)
			(justify left bottom)
		)
	)
	(label "12V_MODE"
		(at 99.06 95.25 0)
		(effects
			(font
				(size 1.27 1.27)
			)
			(justify left bottom)
		)
	)
	(symbol
		(lib_id "antmicropower:GND")
		(at 128.27 250.19 0)
		(unit 1)
		(exclude_from_sim no)
		(in_bom yes)
		(on_board yes)
		(dnp no)
		(fields_autoplaced yes)
		(property "Reference" "#PWR044"
			(at 128.27 250.19 0)
			(effects
				(font
					(size 1.27 1.27)
				)
				(justify left)
				(hide yes)
			)
		)
		(property "Value" "GND"
			(at 128.27 254.635 0)
			(effects
				(font
					(size 1.27 1.27)
				)
			)
		)
		(property "Footprint" ""
			(at 128.27 250.19 0)
			(effects
				(font
					(size 1.27 1.27)
					(thickness 0.15)
				)
				(justify left bottom)
				(hide yes)
			)
		)
		(property "Datasheet" ""
			(at 128.27 250.19 0)
			(effects
				(font
					(size 1.27 1.27)
					(thickness 0.15)
				)
				(justify left bottom)
				(hide yes)
			)
		)
		(property "Description" ""
			(at 128.27 250.19 0)
			(effects
				(font
					(size 1.27 1.27)
				)
				(hide yes)
			)
		)
		(property "Author" "Antmicro"
			(at 137.16 257.81 0)
			(effects
				(font
					(size 1.27 1.27)
					(thickness 0.15)
				)
				(justify left bottom)
				(hide yes)
			)
		)
		(property "License" "Apache-2.0"
			(at 137.16 260.35 0)
			(effects
				(font
					(size 1.27 1.27)
					(thickness 0.15)
				)
				(justify left bottom)
				(hide yes)
			)
		)
		(pin "1"
		)
		(instances
			(project "usb-c-power-adapter"
				(path ""
					(reference "#PWR044")
					(unit 1)
				)
			)
		)
	)
	(symbol
		(lib_id "antmicropower:GND")
		(at 213.36 186.69 0)
		(unit 1)
		(exclude_from_sim no)
		(in_bom yes)
		(on_board yes)
		(dnp no)
		(fields_autoplaced yes)
		(property "Reference" "#PWR078"
			(at 222.25 189.23 0)
			(effects
				(font
					(size 1.27 1.27)
					(thickness 0.15)
				)
				(justify left bottom)
				(hide yes)
			)
		)
		(property "Value" "GND"
			(at 213.36 191.135 0)
			(effects
				(font
					(size 1.27 1.27)
					(thickness 0.15)
				)
			)
		)
		(property "Footprint" ""
			(at 222.25 194.31 0)
			(effects
				(font
					(size 1.27 1.27)
					(thickness 0.15)
				)
				(justify left bottom)
				(hide yes)
			)
		)
		(property "Datasheet" ""
			(at 222.25 199.39 0)
			(effects
				(font
					(size 1.27 1.27)
					(thickness 0.15)
				)
				(justify left bottom)
				(hide yes)
			)
		)
		(property "Description" ""
			(at 213.36 186.69 0)
			(effects
				(font
					(size 1.27 1.27)
				)
				(hide yes)
			)
		)
		(property "Author" "Antmicro"
			(at 222.25 194.31 0)
			(effects
				(font
					(size 1.27 1.27)
					(thickness 0.15)
				)
				(justify left bottom)
				(hide yes)
			)
		)
		(property "License" "Apache-2.0"
			(at 222.25 196.85 0)
			(effects
				(font
					(size 1.27 1.27)
					(thickness 0.15)
				)
				(justify left bottom)
				(hide yes)
			)
		)
		(pin "1"
		)
		(instances
			(project "usb-c-power-adapter"
				(path ""
					(reference "#PWR078")
					(unit 1)
				)
			)
		)
	)
	(symbol
		(lib_id "antmicroCapacitorsmisc:C_22u_25V_0805")
		(at 278.13 76.2 90)
		(unit 1)
		(exclude_from_sim no)
		(in_bom yes)
		(on_board yes)
		(dnp no)
		(fields_autoplaced yes)
		(property "Reference" "C30"
			(at 280.67 71.1136 90)
			(effects
				(font
					(size 1.27 1.27)
					(thickness 0.15)
				)
				(justify right)
			)
		)
		(property "Value" "C_22u_25V_0805"
			(at 288.29 55.88 0)
			(effects
				(font
					(size 1.27 1.27)
					(thickness 0.15)
				)
				(justify left bottom)
				(hide yes)
			)
		)
		(property "Footprint" "antmicro-footprints:C_0805_2012Metric"
			(at 290.83 55.88 0)
			(effects
				(font
					(size 1.27 1.27)
					(thickness 0.15)
				)
				(justify left bottom)
				(hide yes)
			)
		)
		(property "Datasheet" "https://product.samsungsem.com/mlcc/CL21A226MAYNNN.do"
			(at 293.37 55.88 0)
			(effects
				(font
					(size 1.27 1.27)
					(thickness 0.15)
				)
				(justify left bottom)
				(hide yes)
			)
		)
		(property "Description" "SMT Multilayer Ceramic Capacitor, 22uF, +/-20%, 25V, X5R, 0805 [2012 Metric]"
			(at 278.13 76.2 0)
			(effects
				(font
					(size 1.27 1.27)
				)
				(hide yes)
			)
		)
		(property "MPN" "CL21A226MAYNNNE"
			(at 295.91 55.88 0)
			(effects
				(font
					(size 1.27 1.27)
					(thickness 0.15)
				)
				(justify left bottom)
				(hide yes)
			)
		)
		(property "Manufacturer" "Samsung Electro-Mechanics"
			(at 298.45 55.88 0)
			(effects
				(font
					(size 1.27 1.27)
					(thickness 0.15)
				)
				(justify left bottom)
				(hide yes)
			)
		)
		(property "License" "Apache-2.0"
			(at 300.99 55.88 0)
			(effects
				(font
					(size 1.27 1.27)
					(thickness 0.15)
				)
				(justify left bottom)
				(hide yes)
			)
		)
		(property "Author" "Antmicro"
			(at 303.53 55.88 0)
			(effects
				(font
					(size 1.27 1.27)
					(thickness 0.15)
				)
				(justify left bottom)
				(hide yes)
			)
		)
		(property "Val" "22u"
			(at 280.67 73.6536 90)
			(effects
				(font
					(size 1.27 1.27)
					(thickness 0.15)
				)
				(justify right)
			)
		)
		(property "Voltage" "25V"
			(at 280.67 76.1935 90)
			(effects
				(font
					(size 1.27 1.27)
				)
				(justify right)
			)
		)
		(property "Dielectric" "X5R"
			(at 308.61 55.88 0)
			(effects
				(font
					(size 1.27 1.27)
				)
				(justify left bottom)
				(hide yes)
			)
		)
		(property "Public" "False"
			(at 311.15 55.88 0)
			(effects
				(font
					(size 1.27 1.27)
				)
				(justify left bottom)
				(hide yes)
			)
		)
		(pin "1"
		)
		(pin "2"
		)
		(instances
			(project "usb-c-power-adapter"
				(path ""
					(reference "C30")
					(unit 1)
				)
			)
		)
	)
	(symbol
		(lib_id "antmicroResistors0402:R_2k_0402")
		(at 64.77 107.95 270)
		(unit 1)
		(exclude_from_sim no)
		(in_bom yes)
		(on_board yes)
		(dnp no)
		(fields_autoplaced yes)
		(property "Reference" "R5"
			(at 67.31 109.2199 90)
			(effects
				(font
					(size 1.27 1.27)
				)
				(justify left)
			)
		)
		(property "Value" "R_2k_0402"
			(at 60.96 107.95 0)
			(effects
				(font
					(size 1.27 1.27)
				)
				(justify left)
				(hide yes)
			)
		)
		(property "Footprint" "antmicro-footprints:R_0402_1005Metric"
			(at 69.85 113.03 0)
			(effects
				(font
					(size 1.27 1.27)
					(thickness 0.15)
				)
				(justify left bottom)
				(hide yes)
			)
		)
		(property "Datasheet" "https://www.bourns.com/docs/product-datasheets/cr.pdf"
			(at 64.77 107.95 0)
			(effects
				(font
					(size 1.27 1.27)
					(thickness 0.15)
				)
				(justify left bottom)
				(hide yes)
			)
		)
		(property "Description" "SMD Chip Resistor, 2 kohm, ± 1%, 62.5 mW, 0402 [1005 Metric], Thick Film, General Purpose"
			(at 64.77 107.95 0)
			(effects
				(font
					(size 1.27 1.27)
				)
				(hide yes)
			)
		)
		(property "Manufacturer" "Bourns"
			(at 74.93 113.03 0)
			(effects
				(font
					(size 1.27 1.27)
					(thickness 0.15)
				)
				(justify left bottom)
				(hide yes)
			)
		)
		(property "MPN" "CR0402-FX-2001GLF"
			(at 72.39 113.03 0)
			(effects
				(font
					(size 1.27 1.27)
					(thickness 0.15)
				)
				(justify left bottom)
				(hide yes)
			)
		)
		(property "Val" "2k"
			(at 67.31 111.76 90)
			(effects
				(font
					(size 1.27 1.27)
					(thickness 0.15)
				)
				(justify left)
			)
		)
		(property "License" "Apache-2.0"
			(at 39.37 128.27 0)
			(effects
				(font
					(size 1.27 1.27)
					(thickness 0.15)
				)
				(justify left bottom)
				(hide yes)
			)
		)
		(property "Author" "Antmicro"
			(at 36.83 128.27 0)
			(effects
				(font
					(size 1.27 1.27)
					(thickness 0.15)
				)
				(justify left bottom)
				(hide yes)
			)
		)
		(property "Tolerance" "1%"
			(at 54.61 128.27 0)
			(effects
				(font
					(size 1.27 1.27)
				)
				(justify left bottom)
				(hide yes)
			)
		)
		(pin "1"
		)
		(pin "2"
		)
		(instances
			(project "usb-c-power-adapter"
				(path ""
					(reference "R5")
					(unit 1)
				)
			)
		)
	)
	(symbol
		(lib_id "antmicropower:GND")
		(at 382.27 102.87 0)
		(unit 1)
		(exclude_from_sim no)
		(in_bom yes)
		(on_board yes)
		(dnp no)
		(fields_autoplaced yes)
		(property "Reference" "#PWR079"
			(at 382.27 102.87 0)
			(effects
				(font
					(size 1.27 1.27)
				)
				(justify left)
				(hide yes)
			)
		)
		(property "Value" "GND"
			(at 382.27 107.315 0)
			(effects
				(font
					(size 1.27 1.27)
				)
			)
		)
		(property "Footprint" ""
			(at 382.27 102.87 0)
			(effects
				(font
					(size 1.27 1.27)
					(thickness 0.15)
				)
				(justify left bottom)
				(hide yes)
			)
		)
		(property "Datasheet" ""
			(at 382.27 102.87 0)
			(effects
				(font
					(size 1.27 1.27)
					(thickness 0.15)
				)
				(justify left bottom)
				(hide yes)
			)
		)
		(property "Description" ""
			(at 382.27 102.87 0)
			(effects
				(font
					(size 1.27 1.27)
				)
				(hide yes)
			)
		)
		(property "Author" "Antmicro"
			(at 391.16 110.49 0)
			(effects
				(font
					(size 1.27 1.27)
					(thickness 0.15)
				)
				(justify left bottom)
				(hide yes)
			)
		)
		(property "License" "Apache-2.0"
			(at 391.16 113.03 0)
			(effects
				(font
					(size 1.27 1.27)
					(thickness 0.15)
				)
				(justify left bottom)
				(hide yes)
			)
		)
		(pin "1"
		)
		(instances
			(project "usb-c-power-adapter"
				(path ""
					(reference "#PWR079")
					(unit 1)
				)
			)
		)
	)
	(symbol
		(lib_id "antmicropower:+3V3")
		(at 213.36 167.64 0)
		(unit 1)
		(exclude_from_sim no)
		(in_bom yes)
		(on_board yes)
		(dnp no)
		(fields_autoplaced yes)
		(property "Reference" "#PWR077"
			(at 228.6 167.64 0)
			(effects
				(font
					(size 1.27 1.27)
					(thickness 0.15)
				)
				(justify left bottom)
				(hide yes)
			)
		)
		(property "Value" "+3V3"
			(at 213.36 162.56 0)
			(effects
				(font
					(size 1.27 1.27)
					(thickness 0.15)
				)
			)
		)
		(property "Footprint" ""
			(at 228.6 175.26 0)
			(effects
				(font
					(size 1.27 1.27)
					(thickness 0.15)
				)
				(justify left bottom)
				(hide yes)
			)
		)
		(property "Datasheet" ""
			(at 228.6 177.8 0)
			(effects
				(font
					(size 1.27 1.27)
					(thickness 0.15)
				)
				(justify left bottom)
				(hide yes)
			)
		)
		(property "Description" ""
			(at 213.36 167.64 0)
			(effects
				(font
					(size 1.27 1.27)
				)
				(hide yes)
			)
		)
		(property "Author" "Antmicro"
			(at 228.6 170.18 0)
			(effects
				(font
					(size 1.27 1.27)
					(thickness 0.15)
				)
				(justify left bottom)
				(hide yes)
			)
		)
		(property "License" "Apache-2.0"
			(at 228.6 172.72 0)
			(effects
				(font
					(size 1.27 1.27)
					(thickness 0.15)
				)
				(justify left bottom)
				(hide yes)
			)
		)
		(pin "1"
		)
		(instances
			(project "usb-c-power-adapter"
				(path ""
					(reference "#PWR077")
					(unit 1)
				)
			)
		)
	)
	(symbol
		(lib_id "antmicropower:GND")
		(at 96.52 82.55 0)
		(unit 1)
		(exclude_from_sim no)
		(in_bom yes)
		(on_board yes)
		(dnp no)
		(property "Reference" "#PWR012"
			(at 96.52 82.55 0)
			(effects
				(font
					(size 1.27 1.27)
				)
				(justify left)
				(hide yes)
			)
		)
		(property "Value" "GND"
			(at 96.52 86.36 0)
			(effects
				(font
					(size 1.27 1.27)
				)
			)
		)
		(property "Footprint" ""
			(at 96.52 82.55 0)
			(effects
				(font
					(size 1.27 1.27)
					(thickness 0.15)
				)
				(justify left bottom)
				(hide yes)
			)
		)
		(property "Datasheet" ""
			(at 96.52 82.55 0)
			(effects
				(font
					(size 1.27 1.27)
					(thickness 0.15)
				)
				(justify left bottom)
				(hide yes)
			)
		)
		(property "Description" ""
			(at 96.52 82.55 0)
			(effects
				(font
					(size 1.27 1.27)
				)
				(hide yes)
			)
		)
		(property "Author" "Antmicro"
			(at 105.41 90.17 0)
			(effects
				(font
					(size 1.27 1.27)
					(thickness 0.15)
				)
				(justify left bottom)
				(hide yes)
			)
		)
		(property "License" "Apache-2.0"
			(at 105.41 92.71 0)
			(effects
				(font
					(size 1.27 1.27)
					(thickness 0.15)
				)
				(justify left bottom)
				(hide yes)
			)
		)
		(pin "1"
		)
		(instances
			(project "usb-c-power-adapter"
				(path ""
					(reference "#PWR012")
					(unit 1)
				)
			)
		)
	)
	(symbol
		(lib_id "antmicroCapacitorsmisc:C_22u_25V_0805")
		(at 304.8 62.23 90)
		(unit 1)
		(exclude_from_sim no)
		(in_bom yes)
		(on_board yes)
		(dnp no)
		(fields_autoplaced yes)
		(property "Reference" "C38"
			(at 307.34 57.1436 90)
			(effects
				(font
					(size 1.27 1.27)
					(thickness 0.15)
				)
				(justify right)
			)
		)
		(property "Value" "C_22u_25V_0805"
			(at 314.96 41.91 0)
			(effects
				(font
					(size 1.27 1.27)
					(thickness 0.15)
				)
				(justify left bottom)
				(hide yes)
			)
		)
		(property "Footprint" "antmicro-footprints:C_0805_2012Metric"
			(at 317.5 41.91 0)
			(effects
				(font
					(size 1.27 1.27)
					(thickness 0.15)
				)
				(justify left bottom)
				(hide yes)
			)
		)
		(property "Datasheet" "https://product.samsungsem.com/mlcc/CL21A226MAYNNN.do"
			(at 320.04 41.91 0)
			(effects
				(font
					(size 1.27 1.27)
					(thickness 0.15)
				)
				(justify left bottom)
				(hide yes)
			)
		)
		(property "Description" "SMT Multilayer Ceramic Capacitor, 22uF, +/-20%, 25V, X5R, 0805 [2012 Metric]"
			(at 304.8 62.23 0)
			(effects
				(font
					(size 1.27 1.27)
				)
				(hide yes)
			)
		)
		(property "MPN" "CL21A226MAYNNNE"
			(at 322.58 41.91 0)
			(effects
				(font
					(size 1.27 1.27)
					(thickness 0.15)
				)
				(justify left bottom)
				(hide yes)
			)
		)
		(property "Manufacturer" "Samsung Electro-Mechanics"
			(at 325.12 41.91 0)
			(effects
				(font
					(size 1.27 1.27)
					(thickness 0.15)
				)
				(justify left bottom)
				(hide yes)
			)
		)
		(property "License" "Apache-2.0"
			(at 327.66 41.91 0)
			(effects
				(font
					(size 1.27 1.27)
					(thickness 0.15)
				)
				(justify left bottom)
				(hide yes)
			)
		)
		(property "Author" "Antmicro"
			(at 330.2 41.91 0)
			(effects
				(font
					(size 1.27 1.27)
					(thickness 0.15)
				)
				(justify left bottom)
				(hide yes)
			)
		)
		(property "Val" "22u"
			(at 307.34 59.6836 90)
			(effects
				(font
					(size 1.27 1.27)
					(thickness 0.15)
				)
				(justify right)
			)
		)
		(property "Voltage" "25V"
			(at 307.34 62.2235 90)
			(effects
				(font
					(size 1.27 1.27)
				)
				(justify right)
			)
		)
		(property "Dielectric" "X5R"
			(at 335.28 41.91 0)
			(effects
				(font
					(size 1.27 1.27)
				)
				(justify left bottom)
				(hide yes)
			)
		)
		(property "Public" "False"
			(at 337.82 41.91 0)
			(effects
				(font
					(size 1.27 1.27)
				)
				(justify left bottom)
				(hide yes)
			)
		)
		(pin "1"
		)
		(pin "2"
		)
		(instances
			(project "usb-c-power-adapter"
				(path ""
					(reference "C38")
					(unit 1)
				)
			)
		)
	)
	(symbol
		(lib_id "antmicroFixedInductors:L_4u7_14.6A_Abracon-Q8080")
		(at 175.26 73.66 0)
		(unit 1)
		(exclude_from_sim no)
		(in_bom yes)
		(on_board yes)
		(dnp no)
		(fields_autoplaced yes)
		(property "Reference" "L1"
			(at 177.8 68.58 0)
			(effects
				(font
					(size 1.27 1.27)
					(thickness 0.15)
				)
			)
		)
		(property "Value" "L_4u7_14.6A_Abracon-Q8080"
			(at 190.5 83.82 0)
			(effects
				(font
					(size 1.27 1.27)
					(thickness 0.15)
				)
				(justify left bottom)
				(hide yes)
			)
		)
		(property "Footprint" "antmicro-footprints:L_Abracon_ASPIAIG-Q8080"
			(at 190.5 86.36 0)
			(effects
				(font
					(size 1.27 1.27)
					(thickness 0.15)
				)
				(justify left bottom)
				(hide yes)
			)
		)
		(property "Datasheet" "https://www.mouser.com/datasheet/2/3/ASPIAIG_Q8080-2256550.pdf"
			(at 190.5 88.9 0)
			(effects
				(font
					(size 1.27 1.27)
					(thickness 0.15)
				)
				(justify left bottom)
				(hide yes)
			)
		)
		(property "Description" "Power Inductors - SMD 4.7 UH 20%"
			(at 175.26 73.66 0)
			(effects
				(font
					(size 1.27 1.27)
				)
				(hide yes)
			)
		)
		(property "MPN" "ASPIAIG-Q8080-4R7M-T"
			(at 190.5 91.44 0)
			(effects
				(font
					(size 1.27 1.27)
					(thickness 0.15)
				)
				(justify left bottom)
				(hide yes)
			)
		)
		(property "ISat" "17A"
			(at 190.5 93.98 0)
			(effects
				(font
					(size 1.27 1.27)
					(thickness 0.15)
				)
				(justify left bottom)
				(hide yes)
			)
		)
		(property "IMax" "14.6A"
			(at 190.5 96.52 0)
			(effects
				(font
					(size 1.27 1.27)
					(thickness 0.15)
				)
				(justify left bottom)
				(hide yes)
			)
		)
		(property "Size" "8.9x8.5"
			(at 190.5 99.06 0)
			(effects
				(font
					(size 1.27 1.27)
					(thickness 0.15)
				)
				(justify left bottom)
				(hide yes)
			)
		)
		(property "Val" "4.7u/14.6A"
			(at 177.8 71.12 0)
			(effects
				(font
					(size 1.27 1.27)
					(thickness 0.15)
				)
			)
		)
		(property "Author" "Antmicro"
			(at 190.5 101.6 0)
			(effects
				(font
					(size 1.27 1.27)
					(thickness 0.15)
				)
				(justify left bottom)
				(hide yes)
			)
		)
		(property "License" "Apache-2.0"
			(at 190.5 104.14 0)
			(effects
				(font
					(size 1.27 1.27)
					(thickness 0.15)
				)
				(justify left bottom)
				(hide yes)
			)
		)
		(property "Manufacturer" "Abracon"
			(at 190.5 106.68 0)
			(effects
				(font
					(size 1.27 1.27)
					(thickness 0.15)
				)
				(justify left bottom)
				(hide yes)
			)
		)
		(pin "1"
		)
		(pin "2"
		)
		(instances
			(project "usb-c-power-adapter"
				(path ""
					(reference "L1")
					(unit 1)
				)
			)
		)
	)
	(symbol
		(lib_id "antmicropower:GND")
		(at 50.8 191.77 0)
		(unit 1)
		(exclude_from_sim no)
		(in_bom yes)
		(on_board yes)
		(dnp no)
		(property "Reference" "#PWR035"
			(at 50.8 191.77 0)
			(effects
				(font
					(size 1.27 1.27)
				)
				(justify left)
				(hide yes)
			)
		)
		(property "Value" "GND"
			(at 50.8 195.58 0)
			(effects
				(font
					(size 1.27 1.27)
				)
			)
		)
		(property "Footprint" ""
			(at 50.8 191.77 0)
			(effects
				(font
					(size 1.27 1.27)
					(thickness 0.15)
				)
				(justify left bottom)
				(hide yes)
			)
		)
		(property "Datasheet" ""
			(at 50.8 191.77 0)
			(effects
				(font
					(size 1.27 1.27)
					(thickness 0.15)
				)
				(justify left bottom)
				(hide yes)
			)
		)
		(property "Description" ""
			(at 50.8 191.77 0)
			(effects
				(font
					(size 1.27 1.27)
				)
				(hide yes)
			)
		)
		(property "Author" "Antmicro"
			(at 59.69 199.39 0)
			(effects
				(font
					(size 1.27 1.27)
					(thickness 0.15)
				)
				(justify left bottom)
				(hide yes)
			)
		)
		(property "License" "Apache-2.0"
			(at 59.69 201.93 0)
			(effects
				(font
					(size 1.27 1.27)
					(thickness 0.15)
				)
				(justify left bottom)
				(hide yes)
			)
		)
		(pin "1"
		)
		(instances
			(project "usb-c-power-adapter"
				(path ""
					(reference "#PWR035")
					(unit 1)
				)
			)
		)
	)
	(symbol
		(lib_id "antmicroCapacitorsmisc:C_47u_25V_1206")
		(at 278.13 91.44 90)
		(unit 1)
		(exclude_from_sim no)
		(in_bom yes)
		(on_board yes)
		(dnp no)
		(fields_autoplaced yes)
		(property "Reference" "C31"
			(at 280.67 86.3536 90)
			(effects
				(font
					(size 1.27 1.27)
					(thickness 0.15)
				)
				(justify right)
			)
		)
		(property "Value" "C_47u_25V_1206"
			(at 290.83 76.2 0)
			(effects
				(font
					(size 1.27 1.27)
					(thickness 0.15)
				)
				(justify left bottom)
				(hide yes)
			)
		)
		(property "Footprint" "antmicro-footprints:C_1206_3216Metric"
			(at 293.37 76.2 0)
			(effects
				(font
					(size 1.27 1.27)
					(thickness 0.15)
				)
				(justify left bottom)
				(hide yes)
			)
		)
		(property "Datasheet" "https://product.tdk.com/en/search/capacitor/ceramic/mlcc/info?part_no=C3216X5R1E476M160AC"
			(at 295.91 76.2 0)
			(effects
				(font
					(size 1.27 1.27)
					(thickness 0.15)
				)
				(justify left bottom)
				(hide yes)
			)
		)
		(property "Description" "SMD Multilayer Ceramic Capacitor, 47 µF, 25 V, 1206 [3216 Metric], ± 20%, X5R"
			(at 278.13 91.44 0)
			(effects
				(font
					(size 1.27 1.27)
				)
				(hide yes)
			)
		)
		(property "MPN" "C3216X5R1E476M160AC"
			(at 298.45 76.2 0)
			(effects
				(font
					(size 1.27 1.27)
					(thickness 0.15)
				)
				(justify left bottom)
				(hide yes)
			)
		)
		(property "Val" "47u"
			(at 280.67 88.8936 90)
			(effects
				(font
					(size 1.27 1.27)
					(thickness 0.15)
				)
				(justify right)
			)
		)
		(property "Voltage" "25V"
			(at 280.67 91.4336 90)
			(effects
				(font
					(size 1.27 1.27)
					(thickness 0.15)
				)
				(justify right)
			)
		)
		(property "Author" "Antmicro"
			(at 300.99 76.2 0)
			(effects
				(font
					(size 1.27 1.27)
					(thickness 0.15)
				)
				(justify left bottom)
				(hide yes)
			)
		)
		(property "License" "Apache-2.0"
			(at 303.53 76.2 0)
			(effects
				(font
					(size 1.27 1.27)
					(thickness 0.15)
				)
				(justify left bottom)
				(hide yes)
			)
		)
		(property "Manufacturer" "TDK"
			(at 306.07 76.2 0)
			(effects
				(font
					(size 1.27 1.27)
					(thickness 0.15)
				)
				(justify left bottom)
				(hide yes)
			)
		)
		(property "Dielectric" "X5R"
			(at 308.61 76.2 0)
			(effects
				(font
					(size 1.27 1.27)
					(thickness 0.15)
				)
				(justify left bottom)
				(hide yes)
			)
		)
		(property "Public" "False"
			(at 311.15 71.12 0)
			(effects
				(font
					(size 1.27 1.27)
				)
				(justify left bottom)
				(hide yes)
			)
		)
		(pin "2"
		)
		(pin "1"
		)
		(instances
			(project "usb-c-power-adapter"
				(path ""
					(reference "C31")
					(unit 1)
				)
			)
		)
	)
	(symbol
		(lib_id "antmicroCapacitorsmisc:C_10u_0805_35V")
		(at 78.74 81.28 90)
		(unit 1)
		(exclude_from_sim no)
		(in_bom yes)
		(on_board yes)
		(dnp no)
		(fields_autoplaced yes)
		(property "Reference" "C4"
			(at 81.28 77.4636 90)
			(effects
				(font
					(size 1.27 1.27)
					(thickness 0.15)
				)
				(justify right)
			)
		)
		(property "Value" "C_10u_0805_35V"
			(at 88.9 60.96 0)
			(effects
				(font
					(size 1.27 1.27)
					(thickness 0.15)
				)
				(justify left bottom)
				(hide yes)
			)
		)
		(property "Footprint" "antmicro-footprints:C_0805_2012Metric"
			(at 91.44 60.96 0)
			(effects
				(font
					(size 1.27 1.27)
					(thickness 0.15)
				)
				(justify left bottom)
				(hide yes)
			)
		)
		(property "Datasheet" "https://www.murata.com/products/productdetail?partno=GRM21BR6YA106KE43%23"
			(at 93.98 60.96 0)
			(effects
				(font
					(size 1.27 1.27)
					(thickness 0.15)
				)
				(justify left bottom)
				(hide yes)
			)
		)
		(property "Description" "SMD Multilayer Ceramic Capacitor, 10 µF, 35 V, 0805 [2012 Metric], ± 10%, X5R, GRM Series"
			(at 78.74 81.28 0)
			(effects
				(font
					(size 1.27 1.27)
				)
				(hide yes)
			)
		)
		(property "MPN" "GRM21BR6YA106KE43L"
			(at 96.52 60.96 0)
			(effects
				(font
					(size 1.27 1.27)
					(thickness 0.15)
				)
				(justify left bottom)
				(hide yes)
			)
		)
		(property "Manufacturer" "Murata"
			(at 99.06 60.96 0)
			(effects
				(font
					(size 1.27 1.27)
					(thickness 0.15)
				)
				(justify left bottom)
				(hide yes)
			)
		)
		(property "License" "Apache-2.0"
			(at 101.6 60.96 0)
			(effects
				(font
					(size 1.27 1.27)
					(thickness 0.15)
				)
				(justify left bottom)
				(hide yes)
			)
		)
		(property "Author" "Antmicro"
			(at 104.14 60.96 0)
			(effects
				(font
					(size 1.27 1.27)
					(thickness 0.15)
				)
				(justify left bottom)
				(hide yes)
			)
		)
		(property "Val" "10u"
			(at 81.28 80.0036 90)
			(effects
				(font
					(size 1.27 1.27)
					(thickness 0.15)
				)
				(justify right)
			)
		)
		(property "Voltage" "35V"
			(at 106.68 60.96 0)
			(effects
				(font
					(size 1.27 1.27)
				)
				(justify left bottom)
				(hide yes)
			)
		)
		(property "Dielectric" ""
			(at 109.22 60.96 0)
			(effects
				(font
					(size 1.27 1.27)
				)
				(justify left bottom)
				(hide yes)
			)
		)
		(property "Public" "False"
			(at 111.76 60.96 0)
			(effects
				(font
					(size 1.27 1.27)
				)
				(justify left bottom)
				(hide yes)
			)
		)
		(pin "2"
		)
		(pin "1"
		)
		(instances
			(project "usb-c-power-adapter"
				(path ""
					(reference "C4")
					(unit 1)
				)
			)
		)
	)
	(symbol
		(lib_id "antmicropower:GND")
		(at 377.19 63.5 0)
		(unit 1)
		(exclude_from_sim no)
		(in_bom yes)
		(on_board yes)
		(dnp no)
		(fields_autoplaced yes)
		(property "Reference" "#PWR064"
			(at 386.08 66.04 0)
			(effects
				(font
					(size 1.27 1.27)
					(thickness 0.15)
				)
				(justify left bottom)
				(hide yes)
			)
		)
		(property "Value" "GND"
			(at 377.19 67.945 0)
			(effects
				(font
					(size 1.27 1.27)
					(thickness 0.15)
				)
			)
		)
		(property "Footprint" ""
			(at 386.08 71.12 0)
			(effects
				(font
					(size 1.27 1.27)
					(thickness 0.15)
				)
				(justify left bottom)
				(hide yes)
			)
		)
		(property "Datasheet" ""
			(at 386.08 76.2 0)
			(effects
				(font
					(size 1.27 1.27)
					(thickness 0.15)
				)
				(justify left bottom)
				(hide yes)
			)
		)
		(property "Description" ""
			(at 377.19 63.5 0)
			(effects
				(font
					(size 1.27 1.27)
				)
				(hide yes)
			)
		)
		(property "Author" "Antmicro"
			(at 386.08 71.12 0)
			(effects
				(font
					(size 1.27 1.27)
					(thickness 0.15)
				)
				(justify left bottom)
				(hide yes)
			)
		)
		(property "License" "Apache-2.0"
			(at 386.08 73.66 0)
			(effects
				(font
					(size 1.27 1.27)
					(thickness 0.15)
				)
				(justify left bottom)
				(hide yes)
			)
		)
		(pin "1"
		)
		(instances
			(project "usb-c-power-adapter"
				(path ""
					(reference "#PWR064")
					(unit 1)
				)
			)
		)
	)
	(symbol
		(lib_id "antmicroCapacitorsmisc:C_22u_25V_0805")
		(at 287.02 76.2 90)
		(unit 1)
		(exclude_from_sim no)
		(in_bom yes)
		(on_board yes)
		(dnp no)
		(fields_autoplaced yes)
		(property "Reference" "C33"
			(at 289.56 71.1136 90)
			(effects
				(font
					(size 1.27 1.27)
					(thickness 0.15)
				)
				(justify right)
			)
		)
		(property "Value" "C_22u_25V_0805"
			(at 297.18 55.88 0)
			(effects
				(font
					(size 1.27 1.27)
					(thickness 0.15)
				)
				(justify left bottom)
				(hide yes)
			)
		)
		(property "Footprint" "antmicro-footprints:C_0805_2012Metric"
			(at 299.72 55.88 0)
			(effects
				(font
					(size 1.27 1.27)
					(thickness 0.15)
				)
				(justify left bottom)
				(hide yes)
			)
		)
		(property "Datasheet" "https://product.samsungsem.com/mlcc/CL21A226MAYNNN.do"
			(at 302.26 55.88 0)
			(effects
				(font
					(size 1.27 1.27)
					(thickness 0.15)
				)
				(justify left bottom)
				(hide yes)
			)
		)
		(property "Description" "SMT Multilayer Ceramic Capacitor, 22uF, +/-20%, 25V, X5R, 0805 [2012 Metric]"
			(at 287.02 76.2 0)
			(effects
				(font
					(size 1.27 1.27)
				)
				(hide yes)
			)
		)
		(property "MPN" "CL21A226MAYNNNE"
			(at 304.8 55.88 0)
			(effects
				(font
					(size 1.27 1.27)
					(thickness 0.15)
				)
				(justify left bottom)
				(hide yes)
			)
		)
		(property "Manufacturer" "Samsung Electro-Mechanics"
			(at 307.34 55.88 0)
			(effects
				(font
					(size 1.27 1.27)
					(thickness 0.15)
				)
				(justify left bottom)
				(hide yes)
			)
		)
		(property "License" "Apache-2.0"
			(at 309.88 55.88 0)
			(effects
				(font
					(size 1.27 1.27)
					(thickness 0.15)
				)
				(justify left bottom)
				(hide yes)
			)
		)
		(property "Author" "Antmicro"
			(at 312.42 55.88 0)
			(effects
				(font
					(size 1.27 1.27)
					(thickness 0.15)
				)
				(justify left bottom)
				(hide yes)
			)
		)
		(property "Val" "22u"
			(at 289.56 73.6536 90)
			(effects
				(font
					(size 1.27 1.27)
					(thickness 0.15)
				)
				(justify right)
			)
		)
		(property "Voltage" "25V"
			(at 289.56 76.1935 90)
			(effects
				(font
					(size 1.27 1.27)
				)
				(justify right)
			)
		)
		(property "Dielectric" "X5R"
			(at 317.5 55.88 0)
			(effects
				(font
					(size 1.27 1.27)
				)
				(justify left bottom)
				(hide yes)
			)
		)
		(property "Public" "False"
			(at 320.04 55.88 0)
			(effects
				(font
					(size 1.27 1.27)
				)
				(justify left bottom)
				(hide yes)
			)
		)
		(pin "1"
		)
		(pin "2"
		)
		(instances
			(project "usb-c-power-adapter"
				(path ""
					(reference "C33")
					(unit 1)
				)
			)
		)
	)
	(symbol
		(lib_id "antmicropower:GND")
		(at 391.16 102.87 0)
		(unit 1)
		(exclude_from_sim no)
		(in_bom yes)
		(on_board yes)
		(dnp no)
		(fields_autoplaced yes)
		(property "Reference" "#PWR086"
			(at 391.16 102.87 0)
			(effects
				(font
					(size 1.27 1.27)
				)
				(justify left)
				(hide yes)
			)
		)
		(property "Value" "GND"
			(at 391.16 107.315 0)
			(effects
				(font
					(size 1.27 1.27)
				)
			)
		)
		(property "Footprint" ""
			(at 391.16 102.87 0)
			(effects
				(font
					(size 1.27 1.27)
					(thickness 0.15)
				)
				(justify left bottom)
				(hide yes)
			)
		)
		(property "Datasheet" ""
			(at 391.16 102.87 0)
			(effects
				(font
					(size 1.27 1.27)
					(thickness 0.15)
				)
				(justify left bottom)
				(hide yes)
			)
		)
		(property "Description" ""
			(at 391.16 102.87 0)
			(effects
				(font
					(size 1.27 1.27)
				)
				(hide yes)
			)
		)
		(property "Author" "Antmicro"
			(at 400.05 110.49 0)
			(effects
				(font
					(size 1.27 1.27)
					(thickness 0.15)
				)
				(justify left bottom)
				(hide yes)
			)
		)
		(property "License" "Apache-2.0"
			(at 400.05 113.03 0)
			(effects
				(font
					(size 1.27 1.27)
					(thickness 0.15)
				)
				(justify left bottom)
				(hide yes)
			)
		)
		(pin "1"
		)
		(instances
			(project "usb-c-power-adapter"
				(path ""
					(reference "#PWR086")
					(unit 1)
				)
			)
		)
	)
	(symbol
		(lib_id "antmicroTVSDiodes:AXGD10402KR")
		(at 240.03 80.01 90)
		(unit 1)
		(exclude_from_sim no)
		(in_bom yes)
		(on_board yes)
		(dnp no)
		(fields_autoplaced yes)
		(property "Reference" "D2"
			(at 242.57 74.4934 90)
			(effects
				(font
					(size 1.27 1.27)
					(thickness 0.15)
				)
				(justify right)
			)
		)
		(property "Value" "AXGD10402KR"
			(at 250.19 54.61 0)
			(effects
				(font
					(size 1.27 1.27)
					(thickness 0.15)
				)
				(justify left bottom)
				(hide yes)
			)
		)
		(property "Footprint" "antmicro-footprints:D_0402_1005Metric"
			(at 252.73 54.61 0)
			(effects
				(font
					(size 1.27 1.27)
					(thickness 0.15)
				)
				(justify left bottom)
				(hide yes)
			)
		)
		(property "Datasheet" "https://www.littelfuse.com/media?resourcetype=datasheets&itemid=020b2bf2-064c-4ff1-a898-b4ec805b2fea&filename=littelfuse-xtremeguard-axgd-datasheet"
			(at 255.27 54.61 0)
			(effects
				(font
					(size 1.27 1.27)
					(thickness 0.15)
				)
				(justify left bottom)
				(hide yes)
			)
		)
		(property "Description" "Bidirectional TVS, 30 kV,  0402, 24 V, 0.04 pF"
			(at 240.03 80.01 0)
			(effects
				(font
					(size 1.27 1.27)
				)
				(hide yes)
			)
		)
		(property "Manufacturer" "Littelfuse"
			(at 257.81 54.61 0)
			(effects
				(font
					(size 1.27 1.27)
					(thickness 0.15)
				)
				(justify left bottom)
				(hide yes)
			)
		)
		(property "MPN" "AXGD10402KR"
			(at 242.57 77.0334 90)
			(effects
				(font
					(size 1.27 1.27)
					(thickness 0.15)
				)
				(justify right)
			)
		)
		(property "Author" "Antmicro"
			(at 260.35 54.61 0)
			(effects
				(font
					(size 1.27 1.27)
					(thickness 0.15)
				)
				(justify left bottom)
				(hide yes)
			)
		)
		(property "License" "Apache-2.0"
			(at 262.89 54.61 0)
			(effects
				(font
					(size 1.27 1.27)
					(thickness 0.15)
				)
				(justify left bottom)
				(hide yes)
			)
		)
		(pin "2"
		)
		(pin "1"
		)
		(instances
			(project "usb-c-power-adapter"
				(path ""
					(reference "D2")
					(unit 1)
				)
			)
		)
	)
	(symbol
		(lib_id "antmicropower:+3V3")
		(at 368.3 93.98 0)
		(unit 1)
		(exclude_from_sim no)
		(in_bom yes)
		(on_board yes)
		(dnp no)
		(fields_autoplaced yes)
		(property "Reference" "#PWR071"
			(at 383.54 93.98 0)
			(effects
				(font
					(size 1.27 1.27)
					(thickness 0.15)
				)
				(justify left bottom)
				(hide yes)
			)
		)
		(property "Value" "+3V3"
			(at 368.3 88.9 0)
			(effects
				(font
					(size 1.27 1.27)
					(thickness 0.15)
				)
			)
		)
		(property "Footprint" ""
			(at 383.54 101.6 0)
			(effects
				(font
					(size 1.27 1.27)
					(thickness 0.15)
				)
				(justify left bottom)
				(hide yes)
			)
		)
		(property "Datasheet" ""
			(at 383.54 104.14 0)
			(effects
				(font
					(size 1.27 1.27)
					(thickness 0.15)
				)
				(justify left bottom)
				(hide yes)
			)
		)
		(property "Description" ""
			(at 368.3 93.98 0)
			(effects
				(font
					(size 1.27 1.27)
				)
				(hide yes)
			)
		)
		(property "Author" "Antmicro"
			(at 383.54 96.52 0)
			(effects
				(font
					(size 1.27 1.27)
					(thickness 0.15)
				)
				(justify left bottom)
				(hide yes)
			)
		)
		(property "License" "Apache-2.0"
			(at 383.54 99.06 0)
			(effects
				(font
					(size 1.27 1.27)
					(thickness 0.15)
				)
				(justify left bottom)
				(hide yes)
			)
		)
		(pin "1"
		)
		(instances
			(project "usb-c-power-adapter"
				(path ""
					(reference "#PWR071")
					(unit 1)
				)
			)
		)
	)
	(symbol
		(lib_id "antmicropower:GND")
		(at 71.12 191.77 0)
		(unit 1)
		(exclude_from_sim no)
		(in_bom yes)
		(on_board yes)
		(dnp no)
		(property "Reference" "#PWR037"
			(at 71.12 191.77 0)
			(effects
				(font
					(size 1.27 1.27)
				)
				(justify left)
				(hide yes)
			)
		)
		(property "Value" "GND"
			(at 71.12 195.58 0)
			(effects
				(font
					(size 1.27 1.27)
				)
			)
		)
		(property "Footprint" ""
			(at 71.12 191.77 0)
			(effects
				(font
					(size 1.27 1.27)
					(thickness 0.15)
				)
				(justify left bottom)
				(hide yes)
			)
		)
		(property "Datasheet" ""
			(at 71.12 191.77 0)
			(effects
				(font
					(size 1.27 1.27)
					(thickness 0.15)
				)
				(justify left bottom)
				(hide yes)
			)
		)
		(property "Description" ""
			(at 71.12 191.77 0)
			(effects
				(font
					(size 1.27 1.27)
				)
				(hide yes)
			)
		)
		(property "Author" "Antmicro"
			(at 80.01 199.39 0)
			(effects
				(font
					(size 1.27 1.27)
					(thickness 0.15)
				)
				(justify left bottom)
				(hide yes)
			)
		)
		(property "License" "Apache-2.0"
			(at 80.01 201.93 0)
			(effects
				(font
					(size 1.27 1.27)
					(thickness 0.15)
				)
				(justify left bottom)
				(hide yes)
			)
		)
		(pin "1"
		)
		(instances
			(project "usb-c-power-adapter"
				(path ""
					(reference "#PWR037")
					(unit 1)
				)
			)
		)
	)
	(symbol
		(lib_id "antmicropower:+12V")
		(at 347.98 48.26 0)
		(unit 1)
		(exclude_from_sim no)
		(in_bom yes)
		(on_board yes)
		(dnp no)
		(fields_autoplaced yes)
		(property "Reference" "#PWR058"
			(at 347.98 52.07 0)
			(effects
				(font
					(size 1.27 1.27)
				)
				(hide yes)
			)
		)
		(property "Value" "+12V"
			(at 347.98 43.18 0)
			(effects
				(font
					(size 1.27 1.27)
				)
			)
		)
		(property "Footprint" ""
			(at 347.98 48.26 0)
			(effects
				(font
					(size 1.27 1.27)
				)
				(hide yes)
			)
		)
		(property "Datasheet" ""
			(at 347.98 48.26 0)
			(effects
				(font
					(size 1.27 1.27)
				)
				(hide yes)
			)
		)
		(property "Description" ""
			(at 347.98 48.26 0)
			(effects
				(font
					(size 1.27 1.27)
				)
				(hide yes)
			)
		)
		(pin "1"
		)
		(instances
			(project "usb-c-power-adapter"
				(path ""
					(reference "#PWR058")
					(unit 1)
				)
			)
		)
	)
	(symbol
		(lib_id "antmicropower:VCC")
		(at 36.83 55.88 0)
		(unit 1)
		(exclude_from_sim no)
		(in_bom yes)
		(on_board yes)
		(dnp no)
		(fields_autoplaced yes)
		(property "Reference" "#PWR01"
			(at 36.83 59.69 0)
			(effects
				(font
					(size 1.27 1.27)
				)
				(hide yes)
			)
		)
		(property "Value" "VCC"
			(at 36.83 50.8 0)
			(effects
				(font
					(size 1.27 1.27)
				)
			)
		)
		(property "Footprint" ""
			(at 36.83 55.88 0)
			(effects
				(font
					(size 1.27 1.27)
				)
				(hide yes)
			)
		)
		(property "Datasheet" ""
			(at 36.83 55.88 0)
			(effects
				(font
					(size 1.27 1.27)
				)
				(hide yes)
			)
		)
		(property "Description" ""
			(at 36.83 55.88 0)
			(effects
				(font
					(size 1.27 1.27)
				)
				(hide yes)
			)
		)
		(pin "1"
		)
		(instances
			(project "usb-c-power-adapter"
				(path ""
					(reference "#PWR01")
					(unit 1)
				)
			)
		)
	)
	(symbol
		(lib_id "antmicroLEDIndicationDiscrete:LED_G_0603_LG_L29K-G2J1-24-Z")
		(at 177.8 184.15 90)
		(unit 1)
		(exclude_from_sim no)
		(in_bom yes)
		(on_board yes)
		(dnp no)
		(fields_autoplaced yes)
		(property "Reference" "D4"
			(at 180.34 180.34 90)
			(effects
				(font
					(size 1.27 1.27)
					(thickness 0.15)
				)
				(justify right)
			)
		)
		(property "Value" "LED_G_0603_LG_L29K-G2J1-24-Z"
			(at 185.42 163.83 0)
			(effects
				(font
					(size 1.27 1.27)
					(thickness 0.15)
				)
				(justify left bottom)
				(hide yes)
			)
		)
		(property "Footprint" "antmicro-footprints:LED_0603_1608Metric_G"
			(at 187.96 163.83 0)
			(effects
				(font
					(size 1.27 1.27)
					(thickness 0.15)
				)
				(justify left bottom)
				(hide yes)
			)
		)
		(property "Datasheet" "https://look.ams-osram.com/m/19ee86b3ae0ee95b/original/LG-L29K.pdf"
			(at 190.5 163.83 0)
			(effects
				(font
					(size 1.27 1.27)
					(thickness 0.15)
				)
				(justify left bottom)
				(hide yes)
			)
		)
		(property "Description" "LED, Green, SMD, 0603, 20 mA, 1.7 V, 570 nm"
			(at 177.8 184.15 0)
			(effects
				(font
					(size 1.27 1.27)
				)
				(hide yes)
			)
		)
		(property "MPN" "LG L29K-G2J1-24-Z"
			(at 193.04 163.83 0)
			(effects
				(font
					(size 1.27 1.27)
					(thickness 0.15)
				)
				(justify left bottom)
				(hide yes)
			)
		)
		(property "Manufacturer" "OSRAM"
			(at 195.58 163.83 0)
			(effects
				(font
					(size 1.27 1.27)
					(thickness 0.15)
				)
				(justify left bottom)
				(hide yes)
			)
		)
		(property "Color" "Green"
			(at 180.34 182.8799 90)
			(effects
				(font
					(size 1.27 1.27)
				)
				(justify right)
			)
		)
		(property "Author" "Antmicro"
			(at 198.12 163.83 0)
			(effects
				(font
					(size 1.27 1.27)
					(thickness 0.15)
				)
				(justify left bottom)
				(hide yes)
			)
		)
		(property "License" "Apache-2.0"
			(at 200.66 163.83 0)
			(effects
				(font
					(size 1.27 1.27)
					(thickness 0.15)
				)
				(justify left bottom)
				(hide yes)
			)
		)
		(pin "2"
		)
		(pin "1"
		)
		(instances
			(project "usb-c-power-adapter"
				(path ""
					(reference "D4")
					(unit 1)
				)
			)
		)
	)
	(symbol
		(lib_id "antmicropower:GND")
		(at 46.99 116.84 0)
		(mirror y)
		(unit 1)
		(exclude_from_sim no)
		(in_bom yes)
		(on_board yes)
		(dnp no)
		(fields_autoplaced yes)
		(property "Reference" "#PWR02"
			(at 46.99 116.84 0)
			(effects
				(font
					(size 1.27 1.27)
				)
				(justify left)
				(hide yes)
			)
		)
		(property "Value" "GND"
			(at 46.99 121.92 0)
			(effects
				(font
					(size 1.27 1.27)
				)
			)
		)
		(property "Footprint" ""
			(at 46.99 116.84 0)
			(effects
				(font
					(size 1.27 1.27)
					(thickness 0.15)
				)
				(justify left bottom)
				(hide yes)
			)
		)
		(property "Datasheet" ""
			(at 46.99 116.84 0)
			(effects
				(font
					(size 1.27 1.27)
					(thickness 0.15)
				)
				(justify left bottom)
				(hide yes)
			)
		)
		(property "Description" ""
			(at 46.99 116.84 0)
			(effects
				(font
					(size 1.27 1.27)
				)
				(hide yes)
			)
		)
		(property "Author" "Antmicro"
			(at 38.1 124.46 0)
			(effects
				(font
					(size 1.27 1.27)
					(thickness 0.15)
				)
				(justify left bottom)
				(hide yes)
			)
		)
		(property "License" "Apache-2.0"
			(at 38.1 127 0)
			(effects
				(font
					(size 1.27 1.27)
					(thickness 0.15)
				)
				(justify left bottom)
				(hide yes)
			)
		)
		(pin "1"
		)
		(instances
			(project "usb-c-power-adapter"
				(path ""
					(reference "#PWR02")
					(unit 1)
				)
			)
		)
	)
	(symbol
		(lib_id "antmicroTVSDiodes:SZSMF4L14AT3G")
		(at 361.95 55.88 270)
		(unit 1)
		(exclude_from_sim no)
		(in_bom yes)
		(on_board yes)
		(dnp no)
		(property "Reference" "D5"
			(at 359.41 57.15 90)
			(effects
				(font
					(size 1.27 1.27)
					(thickness 0.15)
				)
				(justify right)
			)
		)
		(property "Value" "SZSMF4L12AT3G"
			(at 365.76 64.77 0)
			(effects
				(font
					(size 1.27 1.27)
					(thickness 0.15)
				)
				(justify right)
				(hide yes)
			)
		)
		(property "Footprint" "antmicro-footprints:SOD-123FL"
			(at 351.79 82.55 0)
			(effects
				(font
					(size 1.27 1.27)
					(thickness 0.15)
				)
				(justify left bottom)
				(hide yes)
			)
		)
		(property "Datasheet" "https://www.mouser.com/datasheet/2/240/media-3320461.pdf"
			(at 349.25 82.55 0)
			(effects
				(font
					(size 1.27 1.27)
					(thickness 0.15)
				)
				(justify left bottom)
				(hide yes)
			)
		)
		(property "Description" "ESD, TVS Diode, 14V, UNI, 400W, SOD-123FL"
			(at 361.95 55.88 0)
			(effects
				(font
					(size 1.27 1.27)
				)
				(hide yes)
			)
		)
		(property "MPN" "SZSMF4L12AT3G"
			(at 359.41 59.69 90)
			(effects
				(font
					(size 1.27 1.27)
					(thickness 0.15)
				)
				(justify right)
			)
		)
		(property "Author" "Antmicro"
			(at 341.63 82.55 0)
			(effects
				(font
					(size 1.27 1.27)
					(thickness 0.15)
				)
				(justify left bottom)
				(hide yes)
			)
		)
		(property "License" "Apache-2.0"
			(at 339.09 82.55 0)
			(effects
				(font
					(size 1.27 1.27)
					(thickness 0.15)
				)
				(justify left bottom)
				(hide yes)
			)
		)
		(property "Manufacturer" "Littelfuse"
			(at 339.09 71.12 0)
			(effects
				(font
					(size 1.27 1.27)
					(thickness 0.15)
				)
				(justify left bottom)
				(hide yes)
			)
		)
		(pin "1"
		)
		(pin "2"
		)
		(instances
			(project "usb-c-power-adapter"
				(path ""
					(reference "D5")
					(unit 1)
				)
			)
		)
	)
	(symbol
		(lib_id "antmicroResistors0402:R_0R_0402")
		(at 149.86 87.63 0)
		(unit 1)
		(exclude_from_sim no)
		(in_bom yes)
		(on_board yes)
		(dnp no)
		(property "Reference" "R12"
			(at 156.21 86.36 0)
			(effects
				(font
					(size 1.27 1.27)
				)
			)
		)
		(property "Value" "R_0R_0402"
			(at 149.86 91.44 0)
			(effects
				(font
					(size 1.27 1.27)
				)
				(justify left)
				(hide yes)
			)
		)
		(property "Footprint" "antmicro-footprints:R_0402_1005Metric"
			(at 154.94 82.55 0)
			(effects
				(font
					(size 1.27 1.27)
					(thickness 0.15)
				)
				(justify left bottom)
				(hide yes)
			)
		)
		(property "Datasheet" "https://industrial.panasonic.com/cdbs/www-data/pdf/RDA0000/AOA0000C301.pdf"
			(at 149.86 87.63 0)
			(effects
				(font
					(size 1.27 1.27)
					(thickness 0.15)
				)
				(justify left bottom)
				(hide yes)
			)
		)
		(property "Description" "SMD Chip Resistor, Jumper, 0 ohm, 100 mW, 0402 [1005 Metric], Thick Film, General Purpose"
			(at 149.86 87.63 0)
			(effects
				(font
					(size 1.27 1.27)
				)
				(hide yes)
			)
		)
		(property "Manufacturer" "Panasonic"
			(at 154.94 77.47 0)
			(effects
				(font
					(size 1.27 1.27)
					(thickness 0.15)
				)
				(justify left bottom)
				(hide yes)
			)
		)
		(property "MPN" "ERJ2GE0R00X"
			(at 154.94 80.01 0)
			(effects
				(font
					(size 1.27 1.27)
					(thickness 0.15)
				)
				(justify left bottom)
				(hide yes)
			)
		)
		(property "Val" "0R"
			(at 151.13 88.392 0)
			(effects
				(font
					(size 1.27 1.27)
					(thickness 0.15)
				)
				(justify left bottom)
			)
		)
		(property "License" "Apache-2.0"
			(at 170.18 113.03 0)
			(effects
				(font
					(size 1.27 1.27)
					(thickness 0.15)
				)
				(justify left bottom)
				(hide yes)
			)
		)
		(property "Author" "Antmicro"
			(at 170.18 115.57 0)
			(effects
				(font
					(size 1.27 1.27)
					(thickness 0.15)
				)
				(justify left bottom)
				(hide yes)
			)
		)
		(property "Tolerance" "~"
			(at 170.18 97.79 0)
			(effects
				(font
					(size 1.27 1.27)
				)
				(justify left bottom)
				(hide yes)
			)
		)
		(property "Current" "1A"
			(at 152.4 87.63 0)
			(effects
				(font
					(size 1.27 1.27)
					(thickness 0.15)
				)
				(justify left bottom)
				(hide yes)
			)
		)
		(pin "1"
		)
		(pin "2"
		)
		(instances
			(project "usb-c-power-adapter"
				(path ""
					(reference "R12")
					(unit 1)
				)
			)
		)
	)
	(symbol
		(lib_id "antmicroDCDCConverters:AP62301Z6-7")
		(at 86.36 170.18 0)
		(unit 1)
		(exclude_from_sim no)
		(in_bom yes)
		(on_board yes)
		(dnp no)
		(fields_autoplaced yes)
		(property "Reference" "U3"
			(at 93.98 162.56 0)
			(effects
				(font
					(size 1.27 1.27)
					(thickness 0.15)
				)
			)
		)
		(property "Value" "AP62301Z6-7"
			(at 116.84 180.34 0)
			(effects
				(font
					(size 1.27 1.27)
					(thickness 0.15)
				)
				(justify left bottom)
				(hide yes)
			)
		)
		(property "Footprint" "antmicro-footprints:SOT-563"
			(at 116.84 182.88 0)
			(effects
				(font
					(size 1.27 1.27)
					(thickness 0.15)
				)
				(justify left bottom)
				(hide yes)
			)
		)
		(property "Datasheet" "https://www.diodes.com/assets/Datasheets/AP62300_AP62301_AP62300T.pdf"
			(at 116.84 185.42 0)
			(effects
				(font
					(size 1.27 1.27)
					(thickness 0.15)
				)
				(justify left bottom)
				(hide yes)
			)
		)
		(property "Description" "DC-DC Switching Synchronous Buck Regulator, Adjustable, 4.2V-18Vin, 0.8V-7V/3A out, SOT-563-6"
			(at 86.36 170.18 0)
			(effects
				(font
					(size 1.27 1.27)
				)
				(hide yes)
			)
		)
		(property "MPN" "AP62301Z6-7"
			(at 93.98 165.1 0)
			(effects
				(font
					(size 1.27 1.27)
					(thickness 0.15)
				)
				(justify left bottom)
			)
		)
		(property "Manufacturer" "Diodes Incorporated"
			(at 116.84 187.96 0)
			(effects
				(font
					(size 1.27 1.27)
					(thickness 0.15)
				)
				(justify left bottom)
				(hide yes)
			)
		)
		(property "Author" "Antmicro"
			(at 116.84 190.5 0)
			(effects
				(font
					(size 1.27 1.27)
					(thickness 0.15)
				)
				(justify left bottom)
				(hide yes)
			)
		)
		(property "License" "Apache-2.0"
			(at 116.84 193.04 0)
			(effects
				(font
					(size 1.27 1.27)
					(thickness 0.15)
				)
				(justify left bottom)
				(hide yes)
			)
		)
		(pin "2"
		)
		(pin "1"
		)
		(pin "5"
		)
		(pin "3"
		)
		(pin "6"
		)
		(pin "4"
		)
		(instances
			(project "usb-c-power-adapter"
				(path ""
					(reference "U3")
					(unit 1)
				)
			)
		)
	)
	(symbol
		(lib_id "antmicropower:+5V")
		(at 195.58 167.64 0)
		(unit 1)
		(exclude_from_sim no)
		(in_bom yes)
		(on_board yes)
		(dnp no)
		(fields_autoplaced yes)
		(property "Reference" "#PWR075"
			(at 210.82 170.18 0)
			(effects
				(font
					(size 1.27 1.27)
					(thickness 0.15)
				)
				(justify left bottom)
				(hide yes)
			)
		)
		(property "Value" "+5V"
			(at 195.58 162.56 0)
			(effects
				(font
					(size 1.27 1.27)
					(thickness 0.15)
				)
			)
		)
		(property "Footprint" ""
			(at 210.82 175.26 0)
			(effects
				(font
					(size 1.27 1.27)
					(thickness 0.15)
				)
				(justify left bottom)
				(hide yes)
			)
		)
		(property "Datasheet" ""
			(at 210.82 177.8 0)
			(effects
				(font
					(size 1.27 1.27)
					(thickness 0.15)
				)
				(justify left bottom)
				(hide yes)
			)
		)
		(property "Description" ""
			(at 195.58 167.64 0)
			(effects
				(font
					(size 1.27 1.27)
				)
				(hide yes)
			)
		)
		(property "Author" "Antmicro"
			(at 210.82 175.26 0)
			(effects
				(font
					(size 1.27 1.27)
					(thickness 0.15)
				)
				(justify left bottom)
				(hide yes)
			)
		)
		(property "License" "Apache-2.0"
			(at 210.82 177.8 0)
			(effects
				(font
					(size 1.27 1.27)
					(thickness 0.15)
				)
				(justify left bottom)
				(hide yes)
			)
		)
		(pin "1"
		)
		(instances
			(project "usb-c-power-adapter"
				(path ""
					(reference "#PWR075")
					(unit 1)
				)
			)
		)
	)
	(symbol
		(lib_id "antmicroCapacitors0603:C_10u_25V_0603")
		(at 139.7 240.03 90)
		(unit 1)
		(exclude_from_sim no)
		(in_bom yes)
		(on_board yes)
		(dnp no)
		(fields_autoplaced yes)
		(property "Reference" "C26"
			(at 142.24 236.2136 90)
			(effects
				(font
					(size 1.27 1.27)
					(thickness 0.15)
				)
				(justify right)
			)
		)
		(property "Value" "C_10u_25V_0603"
			(at 149.86 219.71 0)
			(effects
				(font
					(size 1.27 1.27)
					(thickness 0.15)
				)
				(justify left bottom)
				(hide yes)
			)
		)
		(property "Footprint" "antmicro-footprints:C_0603_1608Metric"
			(at 152.4 219.71 0)
			(effects
				(font
					(size 1.27 1.27)
					(thickness 0.15)
				)
				(justify left bottom)
				(hide yes)
			)
		)
		(property "Datasheet" "https://product.tdk.com/en/search/capacitor/ceramic/mlcc/info?part_no=C1608X5R1E106M080AC"
			(at 154.94 219.71 0)
			(effects
				(font
					(size 1.27 1.27)
					(thickness 0.15)
				)
				(justify left bottom)
				(hide yes)
			)
		)
		(property "Description" "SMD Multilayer Ceramic Capacitor, 10 µF, 25 V, 0603 [1608 Metric], ± 20%, X5R, C"
			(at 139.7 240.03 0)
			(effects
				(font
					(size 1.27 1.27)
				)
				(hide yes)
			)
		)
		(property "MPN" "C1608X5R1E106M080AC"
			(at 157.48 219.71 0)
			(effects
				(font
					(size 1.27 1.27)
					(thickness 0.15)
				)
				(justify left bottom)
				(hide yes)
			)
		)
		(property "Manufacturer" "TDK"
			(at 160.02 219.71 0)
			(effects
				(font
					(size 1.27 1.27)
					(thickness 0.15)
				)
				(justify left bottom)
				(hide yes)
			)
		)
		(property "License" "Apache-2.0"
			(at 162.56 219.71 0)
			(effects
				(font
					(size 1.27 1.27)
					(thickness 0.15)
				)
				(justify left bottom)
				(hide yes)
			)
		)
		(property "Author" "Antmicro"
			(at 165.1 219.71 0)
			(effects
				(font
					(size 1.27 1.27)
					(thickness 0.15)
				)
				(justify left bottom)
				(hide yes)
			)
		)
		(property "Val" "10u"
			(at 142.24 238.7536 90)
			(effects
				(font
					(size 1.27 1.27)
					(thickness 0.15)
				)
				(justify right)
			)
		)
		(property "Voltage" "25V"
			(at 167.64 219.71 0)
			(effects
				(font
					(size 1.27 1.27)
				)
				(justify left bottom)
				(hide yes)
			)
		)
		(property "Dielectric" ""
			(at 170.18 219.71 0)
			(effects
				(font
					(size 1.27 1.27)
				)
				(justify left bottom)
				(hide yes)
			)
		)
		(pin "1"
		)
		(pin "2"
		)
		(instances
			(project "usb-c-power-adapter"
				(path ""
					(reference "C26")
					(unit 1)
				)
			)
		)
	)
	(symbol
		(lib_id "antmicropower:GND")
		(at 80.01 191.77 0)
		(unit 1)
		(exclude_from_sim no)
		(in_bom yes)
		(on_board yes)
		(dnp no)
		(property "Reference" "#PWR039"
			(at 80.01 191.77 0)
			(effects
				(font
					(size 1.27 1.27)
				)
				(justify left)
				(hide yes)
			)
		)
		(property "Value" "GND"
			(at 80.01 195.58 0)
			(effects
				(font
					(size 1.27 1.27)
				)
			)
		)
		(property "Footprint" ""
			(at 80.01 191.77 0)
			(effects
				(font
					(size 1.27 1.27)
					(thickness 0.15)
				)
				(justify left bottom)
				(hide yes)
			)
		)
		(property "Datasheet" ""
			(at 80.01 191.77 0)
			(effects
				(font
					(size 1.27 1.27)
					(thickness 0.15)
				)
				(justify left bottom)
				(hide yes)
			)
		)
		(property "Description" ""
			(at 80.01 191.77 0)
			(effects
				(font
					(size 1.27 1.27)
				)
				(hide yes)
			)
		)
		(property "Author" "Antmicro"
			(at 88.9 199.39 0)
			(effects
				(font
					(size 1.27 1.27)
					(thickness 0.15)
				)
				(justify left bottom)
				(hide yes)
			)
		)
		(property "License" "Apache-2.0"
			(at 88.9 201.93 0)
			(effects
				(font
					(size 1.27 1.27)
					(thickness 0.15)
				)
				(justify left bottom)
				(hide yes)
			)
		)
		(pin "1"
		)
		(instances
			(project "usb-c-power-adapter"
				(path ""
					(reference "#PWR039")
					(unit 1)
				)
			)
		)
	)
	(symbol
		(lib_id "antmicroResistors0402:R_140k_0.1%_0402")
		(at 195.58 91.44 90)
		(unit 1)
		(exclude_from_sim no)
		(in_bom yes)
		(on_board yes)
		(dnp no)
		(fields_autoplaced yes)
		(property "Reference" "R17"
			(at 198.12 87.63 90)
			(effects
				(font
					(size 1.27 1.27)
					(thickness 0.15)
				)
				(justify right)
			)
		)
		(property "Value" "R_140k_0.1%_0402"
			(at 208.28 71.12 0)
			(effects
				(font
					(size 1.27 1.27)
					(thickness 0.15)
				)
				(justify left bottom)
				(hide yes)
			)
		)
		(property "Footprint" "antmicro-footprints:R_0402_1005Metric"
			(at 210.82 71.12 0)
			(effects
				(font
					(size 1.27 1.27)
					(thickness 0.15)
				)
				(justify left bottom)
				(hide yes)
			)
		)
		(property "Datasheet" "https://www.vishay.com/docs/28758/tnpw_e3.pdf"
			(at 213.36 71.12 0)
			(effects
				(font
					(size 1.27 1.27)
					(thickness 0.15)
				)
				(justify left bottom)
				(hide yes)
			)
		)
		(property "Description" "SMD Chip Resistor, Ceramic, 140 kohm, ± 0.1%, 62.5 mW, 0402 [1005 Metric], Thin Film, Precision resistors"
			(at 195.58 91.44 0)
			(effects
				(font
					(size 1.27 1.27)
				)
				(hide yes)
			)
		)
		(property "MPN" "RT0402BRD07140KL"
			(at 205.74 60.96 0)
			(effects
				(font
					(size 1.27 1.27)
					(thickness 0.15)
				)
				(justify left bottom)
				(hide yes)
			)
		)
		(property "Val" "140k"
			(at 198.12 90.17 90)
			(effects
				(font
					(size 1.27 1.27)
					(thickness 0.15)
				)
				(justify right)
			)
		)
		(property "Manufacturer" "YAGEO"
			(at 218.44 71.12 0)
			(effects
				(font
					(size 1.27 1.27)
					(thickness 0.15)
				)
				(justify left bottom)
				(hide yes)
			)
		)
		(property "Tolerance" "0.1%"
			(at 201.93 68.58 0)
			(effects
				(font
					(size 1.27 1.27)
					(thickness 0.15)
				)
				(justify left bottom)
				(hide yes)
			)
		)
		(property "License" "Apache-2.0"
			(at 220.98 71.12 0)
			(effects
				(font
					(size 1.27 1.27)
					(thickness 0.15)
				)
				(justify left bottom)
				(hide yes)
			)
		)
		(property "Author" "Antmicro"
			(at 223.52 71.12 0)
			(effects
				(font
					(size 1.27 1.27)
					(thickness 0.15)
				)
				(justify left bottom)
				(hide yes)
			)
		)
		(pin "2"
		)
		(pin "1"
		)
		(instances
			(project "usb-c-power-adapter"
				(path ""
					(reference "R17")
					(unit 1)
				)
			)
		)
	)
	(symbol
		(lib_id "antmicroCapacitors0402:C_100n_50V_X8L_0402")
		(at 151.13 73.66 180)
		(unit 1)
		(exclude_from_sim no)
		(in_bom yes)
		(on_board yes)
		(dnp no)
		(fields_autoplaced yes)
		(property "Reference" "C10"
			(at 148.5836 67.31 0)
			(effects
				(font
					(size 1.27 1.27)
					(thickness 0.15)
				)
			)
		)
		(property "Value" "C_100n_50V_X8L_0402"
			(at 135.89 50.8 0)
			(effects
				(font
					(size 1.27 1.27)
					(thickness 0.15)
				)
				(justify left bottom)
				(hide yes)
			)
		)
		(property "Footprint" "antmicro-footprints:C_0402_1005Metric"
			(at 135.89 48.26 0)
			(effects
				(font
					(size 1.27 1.27)
					(thickness 0.15)
				)
				(justify left bottom)
				(hide yes)
			)
		)
		(property "Datasheet" "https://www.murata.com/products/productdetail?partno=GCM155L8EH104KE07%23"
			(at 135.89 45.72 0)
			(effects
				(font
					(size 1.27 1.27)
					(thickness 0.15)
				)
				(justify left bottom)
				(hide yes)
			)
		)
		(property "Description" "SMD Multilayer Ceramic Capacitor, 100nF, 50V, 0402, ±10%, X8L"
			(at 151.13 73.66 0)
			(effects
				(font
					(size 1.27 1.27)
				)
				(hide yes)
			)
		)
		(property "MPN" "GCM155L8EH104KE07D"
			(at 135.89 43.18 0)
			(effects
				(font
					(size 1.27 1.27)
					(thickness 0.15)
				)
				(justify left bottom)
				(hide yes)
			)
		)
		(property "Val" "100n"
			(at 148.5836 69.85 0)
			(effects
				(font
					(size 1.27 1.27)
					(thickness 0.15)
				)
			)
		)
		(property "Voltage" "50V"
			(at 135.89 63.5 0)
			(effects
				(font
					(size 1.27 1.27)
					(thickness 0.15)
				)
				(justify left bottom)
				(hide yes)
			)
		)
		(property "Dielectric" "X8L"
			(at 135.89 60.96 0)
			(effects
				(font
					(size 1.27 1.27)
					(thickness 0.15)
				)
				(justify left bottom)
				(hide yes)
			)
		)
		(property "Manufacturer" "Murata"
			(at 135.89 58.42 0)
			(effects
				(font
					(size 1.27 1.27)
					(thickness 0.15)
				)
				(justify left bottom)
				(hide yes)
			)
		)
		(property "License" "Apache-2.0"
			(at 135.89 55.88 0)
			(effects
				(font
					(size 1.27 1.27)
					(thickness 0.15)
				)
				(justify left bottom)
				(hide yes)
			)
		)
		(property "Author" "Antmicro"
			(at 135.89 53.34 0)
			(effects
				(font
					(size 1.27 1.27)
					(thickness 0.15)
				)
				(justify left bottom)
				(hide yes)
			)
		)
		(pin "1"
		)
		(pin "2"
		)
		(instances
			(project "usb-c-power-adapter"
				(path ""
					(reference "C10")
					(unit 1)
				)
			)
		)
	)
	(symbol
		(lib_id "antmicropower:GND")
		(at 139.7 191.77 0)
		(unit 1)
		(exclude_from_sim no)
		(in_bom yes)
		(on_board yes)
		(dnp no)
		(fields_autoplaced yes)
		(property "Reference" "#PWR043"
			(at 139.7 191.77 0)
			(effects
				(font
					(size 1.27 1.27)
				)
				(justify left)
				(hide yes)
			)
		)
		(property "Value" "GND"
			(at 139.7 196.215 0)
			(effects
				(font
					(size 1.27 1.27)
				)
			)
		)
		(property "Footprint" ""
			(at 139.7 191.77 0)
			(effects
				(font
					(size 1.27 1.27)
					(thickness 0.15)
				)
				(justify left bottom)
				(hide yes)
			)
		)
		(property "Datasheet" ""
			(at 139.7 191.77 0)
			(effects
				(font
					(size 1.27 1.27)
					(thickness 0.15)
				)
				(justify left bottom)
				(hide yes)
			)
		)
		(property "Description" ""
			(at 139.7 191.77 0)
			(effects
				(font
					(size 1.27 1.27)
				)
				(hide yes)
			)
		)
		(property "Author" "Antmicro"
			(at 148.59 199.39 0)
			(effects
				(font
					(size 1.27 1.27)
					(thickness 0.15)
				)
				(justify left bottom)
				(hide yes)
			)
		)
		(property "License" "Apache-2.0"
			(at 148.59 201.93 0)
			(effects
				(font
					(size 1.27 1.27)
					(thickness 0.15)
				)
				(justify left bottom)
				(hide yes)
			)
		)
		(pin "1"
		)
		(instances
			(project "usb-c-power-adapter"
				(path ""
					(reference "#PWR043")
					(unit 1)
				)
			)
		)
	)
	(symbol
		(lib_id "antmicroResistors0402:R_15k_0402")
		(at 71.12 186.69 90)
		(unit 1)
		(exclude_from_sim no)
		(in_bom yes)
		(on_board yes)
		(dnp no)
		(fields_autoplaced yes)
		(property "Reference" "R23"
			(at 73.66 182.88 90)
			(effects
				(font
					(size 1.27 1.27)
					(thickness 0.15)
				)
				(justify right)
			)
		)
		(property "Value" "R_15k_0402"
			(at 83.82 166.37 0)
			(effects
				(font
					(size 1.27 1.27)
					(thickness 0.15)
				)
				(justify left bottom)
				(hide yes)
			)
		)
		(property "Footprint" "antmicro-footprints:R_0402_1005Metric"
			(at 86.36 166.37 0)
			(effects
				(font
					(size 1.27 1.27)
					(thickness 0.15)
				)
				(justify left bottom)
				(hide yes)
			)
		)
		(property "Datasheet" "https://www.bourns.com/docs/product-datasheets/cr.pdf"
			(at 88.9 166.37 0)
			(effects
				(font
					(size 1.27 1.27)
					(thickness 0.15)
				)
				(justify left bottom)
				(hide yes)
			)
		)
		(property "Description" "SMD Chip Resistor, 15 kohm, ± 1%, 62.5 mW, 0402 [1005 Metric], Thick Film, General Purpose"
			(at 71.12 186.69 0)
			(effects
				(font
					(size 1.27 1.27)
				)
				(hide yes)
			)
		)
		(property "MPN" "CR0402-FX-1502GLF"
			(at 91.44 166.37 0)
			(effects
				(font
					(size 1.27 1.27)
					(thickness 0.15)
				)
				(justify left bottom)
				(hide yes)
			)
		)
		(property "Manufacturer" "Bourns"
			(at 93.98 166.37 0)
			(effects
				(font
					(size 1.27 1.27)
					(thickness 0.15)
				)
				(justify left bottom)
				(hide yes)
			)
		)
		(property "License" "Apache-2.0"
			(at 96.52 166.37 0)
			(effects
				(font
					(size 1.27 1.27)
					(thickness 0.15)
				)
				(justify left bottom)
				(hide yes)
			)
		)
		(property "Author" "Antmicro"
			(at 99.06 166.37 0)
			(effects
				(font
					(size 1.27 1.27)
					(thickness 0.15)
				)
				(justify left bottom)
				(hide yes)
			)
		)
		(property "Val" "15k"
			(at 73.66 185.42 90)
			(effects
				(font
					(size 1.27 1.27)
					(thickness 0.15)
				)
				(justify right)
			)
		)
		(property "Tolerance" "1%"
			(at 81.28 166.37 0)
			(effects
				(font
					(size 1.27 1.27)
				)
				(justify left bottom)
				(hide yes)
			)
		)
		(pin "1"
		)
		(pin "2"
		)
		(instances
			(project "usb-c-power-adapter"
				(path ""
					(reference "R23")
					(unit 1)
				)
			)
		)
	)
	(symbol
		(lib_id "antmicropower:GND")
		(at 50.8 250.19 0)
		(unit 1)
		(exclude_from_sim no)
		(in_bom yes)
		(on_board yes)
		(dnp no)
		(property "Reference" "#PWR038"
			(at 50.8 250.19 0)
			(effects
				(font
					(size 1.27 1.27)
				)
				(justify left)
				(hide yes)
			)
		)
		(property "Value" "GND"
			(at 50.8 254 0)
			(effects
				(font
					(size 1.27 1.27)
				)
			)
		)
		(property "Footprint" ""
			(at 50.8 250.19 0)
			(effects
				(font
					(size 1.27 1.27)
					(thickness 0.15)
				)
				(justify left bottom)
				(hide yes)
			)
		)
		(property "Datasheet" ""
			(at 50.8 250.19 0)
			(effects
				(font
					(size 1.27 1.27)
					(thickness 0.15)
				)
				(justify left bottom)
				(hide yes)
			)
		)
		(property "Description" ""
			(at 50.8 250.19 0)
			(effects
				(font
					(size 1.27 1.27)
				)
				(hide yes)
			)
		)
		(property "Author" "Antmicro"
			(at 59.69 257.81 0)
			(effects
				(font
					(size 1.27 1.27)
					(thickness 0.15)
				)
				(justify left bottom)
				(hide yes)
			)
		)
		(property "License" "Apache-2.0"
			(at 59.69 260.35 0)
			(effects
				(font
					(size 1.27 1.27)
					(thickness 0.15)
				)
				(justify left bottom)
				(hide yes)
			)
		)
		(pin "1"
		)
		(instances
			(project "usb-c-power-adapter"
				(path ""
					(reference "#PWR038")
					(unit 1)
				)
			)
		)
	)
	(symbol
		(lib_id "antmicroCapacitors0402:C_4u7_25V_0402")
		(at 55.88 113.03 90)
		(unit 1)
		(exclude_from_sim no)
		(in_bom yes)
		(on_board yes)
		(dnp no)
		(fields_autoplaced yes)
		(property "Reference" "C2"
			(at 58.42 109.2136 90)
			(effects
				(font
					(size 1.27 1.27)
					(thickness 0.15)
				)
				(justify right)
			)
		)
		(property "Value" "C_4u7_25V_0402"
			(at 66.04 92.71 0)
			(effects
				(font
					(size 1.27 1.27)
					(thickness 0.15)
				)
				(justify left bottom)
				(hide yes)
			)
		)
		(property "Footprint" "antmicro-footprints:C_0402_1005Metric"
			(at 68.58 92.71 0)
			(effects
				(font
					(size 1.27 1.27)
					(thickness 0.15)
				)
				(justify left bottom)
				(hide yes)
			)
		)
		(property "Datasheet" "https://www.murata.com/products/productdetail?partno=GRM155C61E475ME15%23"
			(at 71.12 92.71 0)
			(effects
				(font
					(size 1.27 1.27)
					(thickness 0.15)
				)
				(justify left bottom)
				(hide yes)
			)
		)
		(property "Description" "SMD Multilayer Ceramic Capacitor"
			(at 55.88 113.03 0)
			(effects
				(font
					(size 1.27 1.27)
				)
				(hide yes)
			)
		)
		(property "MPN" "GRM155C61E475ME15J"
			(at 73.66 92.71 0)
			(effects
				(font
					(size 1.27 1.27)
					(thickness 0.15)
				)
				(justify left bottom)
				(hide yes)
			)
		)
		(property "Manufacturer" "Murata"
			(at 76.2 92.71 0)
			(effects
				(font
					(size 1.27 1.27)
					(thickness 0.15)
				)
				(justify left bottom)
				(hide yes)
			)
		)
		(property "License" "Apache-2.0"
			(at 78.74 92.71 0)
			(effects
				(font
					(size 1.27 1.27)
					(thickness 0.15)
				)
				(justify left bottom)
				(hide yes)
			)
		)
		(property "Author" "Antmicro"
			(at 81.28 92.71 0)
			(effects
				(font
					(size 1.27 1.27)
					(thickness 0.15)
				)
				(justify left bottom)
				(hide yes)
			)
		)
		(property "Val" "4u7"
			(at 58.42 111.7536 90)
			(effects
				(font
					(size 1.27 1.27)
					(thickness 0.15)
				)
				(justify right)
			)
		)
		(property "Voltage" "25V"
			(at 83.82 92.71 0)
			(effects
				(font
					(size 1.27 1.27)
				)
				(justify left bottom)
				(hide yes)
			)
		)
		(property "Dielectric" "X5S"
			(at 86.36 92.71 0)
			(effects
				(font
					(size 1.27 1.27)
				)
				(justify left bottom)
				(hide yes)
			)
		)
		(pin "2"
		)
		(pin "1"
		)
		(instances
			(project "usb-c-power-adapter"
				(path ""
					(reference "C2")
					(unit 1)
				)
			)
		)
	)
	(symbol
		(lib_id "antmicroDCDCConverters:AP62301Z6-7")
		(at 86.36 228.6 0)
		(unit 1)
		(exclude_from_sim no)
		(in_bom yes)
		(on_board yes)
		(dnp no)
		(fields_autoplaced yes)
		(property "Reference" "U4"
			(at 93.98 220.98 0)
			(effects
				(font
					(size 1.27 1.27)
					(thickness 0.15)
				)
			)
		)
		(property "Value" "AP62301Z6-7"
			(at 116.84 238.76 0)
			(effects
				(font
					(size 1.27 1.27)
					(thickness 0.15)
				)
				(justify left bottom)
				(hide yes)
			)
		)
		(property "Footprint" "antmicro-footprints:SOT-563"
			(at 116.84 241.3 0)
			(effects
				(font
					(size 1.27 1.27)
					(thickness 0.15)
				)
				(justify left bottom)
				(hide yes)
			)
		)
		(property "Datasheet" "https://www.diodes.com/assets/Datasheets/AP62300_AP62301_AP62300T.pdf"
			(at 116.84 243.84 0)
			(effects
				(font
					(size 1.27 1.27)
					(thickness 0.15)
				)
				(justify left bottom)
				(hide yes)
			)
		)
		(property "Description" "DC-DC Switching Synchronous Buck Regulator, Adjustable, 4.2V-18Vin, 0.8V-7V/3A out, SOT-563-6"
			(at 86.36 228.6 0)
			(effects
				(font
					(size 1.27 1.27)
				)
				(hide yes)
			)
		)
		(property "MPN" "AP62301Z6-7"
			(at 93.98 223.52 0)
			(effects
				(font
					(size 1.27 1.27)
					(thickness 0.15)
				)
				(justify left bottom)
			)
		)
		(property "Manufacturer" "Diodes Incorporated"
			(at 116.84 246.38 0)
			(effects
				(font
					(size 1.27 1.27)
					(thickness 0.15)
				)
				(justify left bottom)
				(hide yes)
			)
		)
		(property "Author" "Antmicro"
			(at 116.84 248.92 0)
			(effects
				(font
					(size 1.27 1.27)
					(thickness 0.15)
				)
				(justify left bottom)
				(hide yes)
			)
		)
		(property "License" "Apache-2.0"
			(at 116.84 251.46 0)
			(effects
				(font
					(size 1.27 1.27)
					(thickness 0.15)
				)
				(justify left bottom)
				(hide yes)
			)
		)
		(pin "2"
		)
		(pin "1"
		)
		(pin "5"
		)
		(pin "3"
		)
		(pin "6"
		)
		(pin "4"
		)
		(instances
			(project "usb-c-power-adapter"
				(path ""
					(reference "U4")
					(unit 1)
				)
			)
		)
	)
	(symbol
		(lib_id "antmicroResistors0402:R_8k66_0402")
		(at 168.91 81.28 0)
		(unit 1)
		(exclude_from_sim no)
		(in_bom no)
		(on_board yes)
		(dnp yes)
		(fields_autoplaced yes)
		(property "Reference" "R15"
			(at 171.45 74.93 0)
			(effects
				(font
					(size 1.27 1.27)
				)
			)
		)
		(property "Value" "R_8k66_0402"
			(at 168.91 85.09 0)
			(effects
				(font
					(size 1.27 1.27)
				)
				(justify left)
				(hide yes)
			)
		)
		(property "Footprint" "antmicro-footprints:R_0402_1005Metric"
			(at 173.99 76.2 0)
			(effects
				(font
					(size 1.27 1.27)
					(thickness 0.15)
				)
				(justify left bottom)
				(hide yes)
			)
		)
		(property "Datasheet" "https://www.bourns.com/docs/product-datasheets/cr.pdf"
			(at 168.91 81.28 0)
			(effects
				(font
					(size 1.27 1.27)
					(thickness 0.15)
				)
				(justify left bottom)
				(hide yes)
			)
		)
		(property "Description" "SMD Chip Resistor"
			(at 168.91 81.28 0)
			(effects
				(font
					(size 1.27 1.27)
				)
				(hide yes)
			)
		)
		(property "Manufacturer" "Bourns"
			(at 173.99 71.12 0)
			(effects
				(font
					(size 1.27 1.27)
					(thickness 0.15)
				)
				(justify left bottom)
				(hide yes)
			)
		)
		(property "MPN" "CR0402-FX-8661GLF"
			(at 173.99 73.66 0)
			(effects
				(font
					(size 1.27 1.27)
					(thickness 0.15)
				)
				(justify left bottom)
				(hide yes)
			)
		)
		(property "Val" "8k66"
			(at 171.45 77.47 0)
			(effects
				(font
					(size 1.27 1.27)
					(thickness 0.15)
				)
			)
		)
		(property "License" "Apache-2.0"
			(at 189.23 106.68 0)
			(effects
				(font
					(size 1.27 1.27)
					(thickness 0.15)
				)
				(justify left bottom)
				(hide yes)
			)
		)
		(property "Author" "Antmicro"
			(at 189.23 109.22 0)
			(effects
				(font
					(size 1.27 1.27)
					(thickness 0.15)
				)
				(justify left bottom)
				(hide yes)
			)
		)
		(property "Tolerance" "1%"
			(at 189.23 91.44 0)
			(effects
				(font
					(size 1.27 1.27)
				)
				(justify left bottom)
				(hide yes)
			)
		)
		(pin "1"
		)
		(pin "2"
		)
		(instances
			(project "usb-c-power-adapter"
				(path ""
					(reference "R15")
					(unit 1)
				)
			)
		)
	)
	(symbol
		(lib_id "antmicroCapacitors0402:C_1n2_50V_0402")
		(at 175.26 88.9 90)
		(unit 1)
		(exclude_from_sim no)
		(in_bom no)
		(on_board yes)
		(dnp yes)
		(fields_autoplaced yes)
		(property "Reference" "C12"
			(at 177.8 85.0835 90)
			(effects
				(font
					(size 1.27 1.27)
				)
				(justify right)
			)
		)
		(property "Value" "C_1n2_50V_0402"
			(at 179.07 88.9 0)
			(effects
				(font
					(size 1.27 1.27)
				)
				(justify left)
				(hide yes)
			)
		)
		(property "Footprint" "antmicro-footprints:C_0402_1005Metric"
			(at 170.18 83.82 0)
			(effects
				(font
					(size 1.27 1.27)
					(thickness 0.15)
				)
				(justify left bottom)
				(hide yes)
			)
		)
		(property "Datasheet" "https://www.murata.com/products/productdetail?partno=GCM155R71H122KA37%23"
			(at 175.26 88.9 0)
			(effects
				(font
					(size 1.27 1.27)
					(thickness 0.15)
				)
				(justify left bottom)
				(hide yes)
			)
		)
		(property "Description" "SMD Multilayer Ceramic Capacitor, 1200 pF, 50 V, 0402 [1005 Metric], ± 10%, X7R, GCM"
			(at 175.26 88.9 0)
			(effects
				(font
					(size 1.27 1.27)
				)
				(hide yes)
			)
		)
		(property "Manufacturer" "Murata"
			(at 165.1 83.82 0)
			(effects
				(font
					(size 1.27 1.27)
					(thickness 0.15)
				)
				(justify left bottom)
				(hide yes)
			)
		)
		(property "MPN" "GCM155R71H122KA37D"
			(at 167.64 83.82 0)
			(effects
				(font
					(size 1.27 1.27)
					(thickness 0.15)
				)
				(justify left bottom)
				(hide yes)
			)
		)
		(property "Val" "1n2"
			(at 177.8 87.6236 90)
			(effects
				(font
					(size 1.27 1.27)
					(thickness 0.15)
				)
				(justify right)
			)
		)
		(property "License" "Apache-2.0"
			(at 198.12 68.58 0)
			(effects
				(font
					(size 1.27 1.27)
					(thickness 0.15)
				)
				(justify left bottom)
				(hide yes)
			)
		)
		(property "Author" "Antmicro"
			(at 200.66 68.58 0)
			(effects
				(font
					(size 1.27 1.27)
					(thickness 0.15)
				)
				(justify left bottom)
				(hide yes)
			)
		)
		(property "Voltage" "50V"
			(at 203.2 68.58 0)
			(effects
				(font
					(size 1.27 1.27)
				)
				(justify left bottom)
				(hide yes)
			)
		)
		(property "Dielectric" ""
			(at 205.74 68.58 0)
			(effects
				(font
					(size 1.27 1.27)
				)
				(justify left bottom)
				(hide yes)
			)
		)
		(pin "1"
		)
		(pin "2"
		)
		(instances
			(project "usb-c-power-adapter"
				(path ""
					(reference "C12")
					(unit 1)
				)
			)
		)
	)
	(symbol
		(lib_id "antmicroCapacitorsmisc:C_22u_25V_0805")
		(at 295.91 76.2 90)
		(unit 1)
		(exclude_from_sim no)
		(in_bom yes)
		(on_board yes)
		(dnp no)
		(fields_autoplaced yes)
		(property "Reference" "C36"
			(at 298.45 71.1136 90)
			(effects
				(font
					(size 1.27 1.27)
					(thickness 0.15)
				)
				(justify right)
			)
		)
		(property "Value" "C_22u_25V_0805"
			(at 306.07 55.88 0)
			(effects
				(font
					(size 1.27 1.27)
					(thickness 0.15)
				)
				(justify left bottom)
				(hide yes)
			)
		)
		(property "Footprint" "antmicro-footprints:C_0805_2012Metric"
			(at 308.61 55.88 0)
			(effects
				(font
					(size 1.27 1.27)
					(thickness 0.15)
				)
				(justify left bottom)
				(hide yes)
			)
		)
		(property "Datasheet" "https://product.samsungsem.com/mlcc/CL21A226MAYNNN.do"
			(at 311.15 55.88 0)
			(effects
				(font
					(size 1.27 1.27)
					(thickness 0.15)
				)
				(justify left bottom)
				(hide yes)
			)
		)
		(property "Description" "SMT Multilayer Ceramic Capacitor, 22uF, +/-20%, 25V, X5R, 0805 [2012 Metric]"
			(at 295.91 76.2 0)
			(effects
				(font
					(size 1.27 1.27)
				)
				(hide yes)
			)
		)
		(property "MPN" "CL21A226MAYNNNE"
			(at 313.69 55.88 0)
			(effects
				(font
					(size 1.27 1.27)
					(thickness 0.15)
				)
				(justify left bottom)
				(hide yes)
			)
		)
		(property "Manufacturer" "Samsung Electro-Mechanics"
			(at 316.23 55.88 0)
			(effects
				(font
					(size 1.27 1.27)
					(thickness 0.15)
				)
				(justify left bottom)
				(hide yes)
			)
		)
		(property "License" "Apache-2.0"
			(at 318.77 55.88 0)
			(effects
				(font
					(size 1.27 1.27)
					(thickness 0.15)
				)
				(justify left bottom)
				(hide yes)
			)
		)
		(property "Author" "Antmicro"
			(at 321.31 55.88 0)
			(effects
				(font
					(size 1.27 1.27)
					(thickness 0.15)
				)
				(justify left bottom)
				(hide yes)
			)
		)
		(property "Val" "22u"
			(at 298.45 73.6536 90)
			(effects
				(font
					(size 1.27 1.27)
					(thickness 0.15)
				)
				(justify right)
			)
		)
		(property "Voltage" "25V"
			(at 298.45 76.1935 90)
			(effects
				(font
					(size 1.27 1.27)
				)
				(justify right)
			)
		)
		(property "Dielectric" "X5R"
			(at 326.39 55.88 0)
			(effects
				(font
					(size 1.27 1.27)
				)
				(justify left bottom)
				(hide yes)
			)
		)
		(property "Public" "False"
			(at 328.93 55.88 0)
			(effects
				(font
					(size 1.27 1.27)
				)
				(justify left bottom)
				(hide yes)
			)
		)
		(pin "1"
		)
		(pin "2"
		)
		(instances
			(project "usb-c-power-adapter"
				(path ""
					(reference "C36")
					(unit 1)
				)
			)
		)
	)
	(symbol
		(lib_id "antmicroCapacitorspol:C_Pol_150u_30V_Vishay-T59-EE")
		(at 59.69 76.2 270)
		(unit 1)
		(exclude_from_sim no)
		(in_bom yes)
		(on_board yes)
		(dnp no)
		(fields_autoplaced yes)
		(property "Reference" "C43"
			(at 62.23 76.9366 90)
			(effects
				(font
					(size 1.27 1.27)
					(thickness 0.15)
				)
				(justify left)
			)
		)
		(property "Value" "C_Pol_150u_30V_Vishay-T59-EE"
			(at 49.53 91.44 0)
			(effects
				(font
					(size 1.27 1.27)
					(thickness 0.15)
				)
				(justify left bottom)
				(hide yes)
			)
		)
		(property "Footprint" "antmicro-footprints:C_Pol_Vishay-T59-EE"
			(at 46.99 91.44 0)
			(effects
				(font
					(size 1.27 1.27)
					(thickness 0.15)
				)
				(justify left bottom)
				(hide yes)
			)
		)
		(property "Datasheet" "https://www.vishay.com/docs/40191/t59.pdf"
			(at 44.45 91.44 0)
			(effects
				(font
					(size 1.27 1.27)
					(thickness 0.15)
				)
				(justify left bottom)
				(hide yes)
			)
		)
		(property "Description" "Tantalum Capacitors - Polymer 150uF 30volts 20% 75mohms maxESR"
			(at 59.69 76.2 0)
			(effects
				(font
					(size 1.27 1.27)
				)
				(hide yes)
			)
		)
		(property "MPN" "T59EE157M030C0075"
			(at 46.99 90.17 0)
			(effects
				(font
					(size 1.27 1.27)
				)
				(justify left bottom)
				(hide yes)
			)
		)
		(property "Manufacturer" "Vishay"
			(at 41.91 91.44 0)
			(effects
				(font
					(size 1.27 1.27)
					(thickness 0.15)
				)
				(justify left bottom)
				(hide yes)
			)
		)
		(property "Voltage" "30V"
			(at 39.37 91.44 0)
			(effects
				(font
					(size 1.27 1.27)
					(thickness 0.15)
				)
				(justify left bottom)
				(hide yes)
			)
		)
		(property "Val" "150u"
			(at 62.23 79.4766 90)
			(effects
				(font
					(size 1.27 1.27)
					(thickness 0.15)
				)
				(justify left)
			)
		)
		(property "Author" "Antmicro"
			(at 36.83 91.44 0)
			(effects
				(font
					(size 1.27 1.27)
					(thickness 0.15)
				)
				(justify left bottom)
				(hide yes)
			)
		)
		(property "License" "Apache-2.0"
			(at 34.29 91.44 0)
			(effects
				(font
					(size 1.27 1.27)
					(thickness 0.15)
				)
				(justify left bottom)
				(hide yes)
			)
		)
		(property "Dielectric" "template_dielectric"
			(at 34.29 90.17 0)
			(effects
				(font
					(size 1.27 1.27)
				)
				(justify left bottom)
				(hide yes)
			)
		)
		(pin "2"
		)
		(pin "1"
		)
		(instances
			(project "usb-c-power-adapter"
				(path ""
					(reference "C43")
					(unit 1)
				)
			)
		)
	)
	(symbol
		(lib_id "antmicroCapacitorsmisc:C_22u_25V_0805")
		(at 304.8 76.2 90)
		(unit 1)
		(exclude_from_sim no)
		(in_bom yes)
		(on_board yes)
		(dnp no)
		(fields_autoplaced yes)
		(property "Reference" "C39"
			(at 307.34 71.1136 90)
			(effects
				(font
					(size 1.27 1.27)
					(thickness 0.15)
				)
				(justify right)
			)
		)
		(property "Value" "C_22u_25V_0805"
			(at 314.96 55.88 0)
			(effects
				(font
					(size 1.27 1.27)
					(thickness 0.15)
				)
				(justify left bottom)
				(hide yes)
			)
		)
		(property "Footprint" "antmicro-footprints:C_0805_2012Metric"
			(at 317.5 55.88 0)
			(effects
				(font
					(size 1.27 1.27)
					(thickness 0.15)
				)
				(justify left bottom)
				(hide yes)
			)
		)
		(property "Datasheet" "https://product.samsungsem.com/mlcc/CL21A226MAYNNN.do"
			(at 320.04 55.88 0)
			(effects
				(font
					(size 1.27 1.27)
					(thickness 0.15)
				)
				(justify left bottom)
				(hide yes)
			)
		)
		(property "Description" "SMT Multilayer Ceramic Capacitor, 22uF, +/-20%, 25V, X5R, 0805 [2012 Metric]"
			(at 304.8 76.2 0)
			(effects
				(font
					(size 1.27 1.27)
				)
				(hide yes)
			)
		)
		(property "MPN" "CL21A226MAYNNNE"
			(at 322.58 55.88 0)
			(effects
				(font
					(size 1.27 1.27)
					(thickness 0.15)
				)
				(justify left bottom)
				(hide yes)
			)
		)
		(property "Manufacturer" "Samsung Electro-Mechanics"
			(at 325.12 55.88 0)
			(effects
				(font
					(size 1.27 1.27)
					(thickness 0.15)
				)
				(justify left bottom)
				(hide yes)
			)
		)
		(property "License" "Apache-2.0"
			(at 327.66 55.88 0)
			(effects
				(font
					(size 1.27 1.27)
					(thickness 0.15)
				)
				(justify left bottom)
				(hide yes)
			)
		)
		(property "Author" "Antmicro"
			(at 330.2 55.88 0)
			(effects
				(font
					(size 1.27 1.27)
					(thickness 0.15)
				)
				(justify left bottom)
				(hide yes)
			)
		)
		(property "Val" "22u"
			(at 307.34 73.6536 90)
			(effects
				(font
					(size 1.27 1.27)
					(thickness 0.15)
				)
				(justify right)
			)
		)
		(property "Voltage" "25V"
			(at 307.34 76.1935 90)
			(effects
				(font
					(size 1.27 1.27)
				)
				(justify right)
			)
		)
		(property "Dielectric" "X5R"
			(at 335.28 55.88 0)
			(effects
				(font
					(size 1.27 1.27)
				)
				(justify left bottom)
				(hide yes)
			)
		)
		(property "Public" "False"
			(at 337.82 55.88 0)
			(effects
				(font
					(size 1.27 1.27)
				)
				(justify left bottom)
				(hide yes)
			)
		)
		(pin "1"
		)
		(pin "2"
		)
		(instances
			(project "usb-c-power-adapter"
				(path ""
					(reference "C39")
					(unit 1)
				)
			)
		)
	)
	(symbol
		(lib_id "antmicropower:GND")
		(at 59.69 82.55 0)
		(unit 1)
		(exclude_from_sim no)
		(in_bom yes)
		(on_board yes)
		(dnp no)
		(property "Reference" "#PWR090"
			(at 59.69 82.55 0)
			(effects
				(font
					(size 1.27 1.27)
				)
				(justify left)
				(hide yes)
			)
		)
		(property "Value" "GND"
			(at 59.69 86.36 0)
			(effects
				(font
					(size 1.27 1.27)
				)
			)
		)
		(property "Footprint" ""
			(at 59.69 82.55 0)
			(effects
				(font
					(size 1.27 1.27)
					(thickness 0.15)
				)
				(justify left bottom)
				(hide yes)
			)
		)
		(property "Datasheet" ""
			(at 59.69 82.55 0)
			(effects
				(font
					(size 1.27 1.27)
					(thickness 0.15)
				)
				(justify left bottom)
				(hide yes)
			)
		)
		(property "Description" ""
			(at 59.69 82.55 0)
			(effects
				(font
					(size 1.27 1.27)
				)
				(hide yes)
			)
		)
		(property "Author" "Antmicro"
			(at 68.58 90.17 0)
			(effects
				(font
					(size 1.27 1.27)
					(thickness 0.15)
				)
				(justify left bottom)
				(hide yes)
			)
		)
		(property "License" "Apache-2.0"
			(at 68.58 92.71 0)
			(effects
				(font
					(size 1.27 1.27)
					(thickness 0.15)
				)
				(justify left bottom)
				(hide yes)
			)
		)
		(pin "1"
		)
		(instances
			(project "usb-c-power-adapter"
				(path ""
					(reference "#PWR090")
					(unit 1)
				)
			)
		)
	)
	(symbol
		(lib_id "antmicroResistors0402:R_158k_0402")
		(at 106.68 113.03 90)
		(unit 1)
		(exclude_from_sim no)
		(in_bom yes)
		(on_board yes)
		(dnp no)
		(fields_autoplaced yes)
		(property "Reference" "R9"
			(at 109.22 109.22 90)
			(effects
				(font
					(size 1.27 1.27)
					(thickness 0.15)
				)
				(justify right)
			)
		)
		(property "Value" "R_158k_0402"
			(at 119.38 92.71 0)
			(effects
				(font
					(size 1.27 1.27)
					(thickness 0.15)
				)
				(justify left bottom)
				(hide yes)
			)
		)
		(property "Footprint" "antmicro-footprints:R_0402_1005Metric"
			(at 121.92 92.71 0)
			(effects
				(font
					(size 1.27 1.27)
					(thickness 0.15)
				)
				(justify left bottom)
				(hide yes)
			)
		)
		(property "Datasheet" "https://www.bourns.com/docs/product-datasheets/cr.pdf"
			(at 124.46 92.71 0)
			(effects
				(font
					(size 1.27 1.27)
					(thickness 0.15)
				)
				(justify left bottom)
				(hide yes)
			)
		)
		(property "Description" "SMD Chip Resistor, 158 kohm, ± 1%, 100 mW, 0402 [1005 Metric], Thick Film, Precision"
			(at 106.68 113.03 0)
			(effects
				(font
					(size 1.27 1.27)
				)
				(hide yes)
			)
		)
		(property "MPN" "CR0402-FX-1583GLF"
			(at 127 92.71 0)
			(effects
				(font
					(size 1.27 1.27)
					(thickness 0.15)
				)
				(justify left bottom)
				(hide yes)
			)
		)
		(property "Manufacturer" "Bourns"
			(at 129.54 92.71 0)
			(effects
				(font
					(size 1.27 1.27)
					(thickness 0.15)
				)
				(justify left bottom)
				(hide yes)
			)
		)
		(property "License" "Apache-2.0"
			(at 132.08 92.71 0)
			(effects
				(font
					(size 1.27 1.27)
					(thickness 0.15)
				)
				(justify left bottom)
				(hide yes)
			)
		)
		(property "Author" "Antmicro"
			(at 134.62 92.71 0)
			(effects
				(font
					(size 1.27 1.27)
					(thickness 0.15)
				)
				(justify left bottom)
				(hide yes)
			)
		)
		(property "Val" "158k"
			(at 109.22 111.76 90)
			(effects
				(font
					(size 1.27 1.27)
					(thickness 0.15)
				)
				(justify right)
			)
		)
		(property "Tolerance" "1%"
			(at 116.84 92.71 0)
			(effects
				(font
					(size 1.27 1.27)
				)
				(justify left bottom)
				(hide yes)
			)
		)
		(pin "1"
		)
		(pin "2"
		)
		(instances
			(project "usb-c-power-adapter"
				(path ""
					(reference "R9")
					(unit 1)
				)
			)
		)
	)
	(symbol
		(lib_id "antmicropower:+12V")
		(at 269.24 83.82 0)
		(unit 1)
		(exclude_from_sim no)
		(in_bom yes)
		(on_board yes)
		(dnp no)
		(property "Reference" "#PWR016"
			(at 269.24 87.63 0)
			(effects
				(font
					(size 1.27 1.27)
				)
				(hide yes)
			)
		)
		(property "Value" "+12V"
			(at 265.43 81.28 0)
			(effects
				(font
					(size 1.27 1.27)
				)
			)
		)
		(property "Footprint" ""
			(at 269.24 83.82 0)
			(effects
				(font
					(size 1.27 1.27)
				)
				(hide yes)
			)
		)
		(property "Datasheet" ""
			(at 269.24 83.82 0)
			(effects
				(font
					(size 1.27 1.27)
				)
				(hide yes)
			)
		)
		(property "Description" ""
			(at 269.24 83.82 0)
			(effects
				(font
					(size 1.27 1.27)
				)
				(hide yes)
			)
		)
		(pin "1"
		)
		(instances
			(project "usb-c-power-adapter"
				(path ""
					(reference "#PWR016")
					(unit 1)
				)
			)
		)
	)
	(symbol
		(lib_id "antmicropower:GND")
		(at 177.8 116.84 0)
		(mirror y)
		(unit 1)
		(exclude_from_sim no)
		(in_bom yes)
		(on_board yes)
		(dnp no)
		(fields_autoplaced yes)
		(property "Reference" "#PWR024"
			(at 177.8 116.84 0)
			(effects
				(font
					(size 1.27 1.27)
				)
				(justify left)
				(hide yes)
			)
		)
		(property "Value" "GND"
			(at 177.8 121.285 0)
			(effects
				(font
					(size 1.27 1.27)
				)
			)
		)
		(property "Footprint" ""
			(at 177.8 116.84 0)
			(effects
				(font
					(size 1.27 1.27)
					(thickness 0.15)
				)
				(justify left bottom)
				(hide yes)
			)
		)
		(property "Datasheet" ""
			(at 177.8 116.84 0)
			(effects
				(font
					(size 1.27 1.27)
					(thickness 0.15)
				)
				(justify left bottom)
				(hide yes)
			)
		)
		(property "Description" ""
			(at 177.8 116.84 0)
			(effects
				(font
					(size 1.27 1.27)
				)
				(hide yes)
			)
		)
		(property "Author" "Antmicro"
			(at 168.91 124.46 0)
			(effects
				(font
					(size 1.27 1.27)
					(thickness 0.15)
				)
				(justify left bottom)
				(hide yes)
			)
		)
		(property "License" "Apache-2.0"
			(at 168.91 127 0)
			(effects
				(font
					(size 1.27 1.27)
					(thickness 0.15)
				)
				(justify left bottom)
				(hide yes)
			)
		)
		(pin "1"
		)
		(instances
			(project "usb-c-power-adapter"
				(path ""
					(reference "#PWR024")
					(unit 1)
				)
			)
		)
	)
	(symbol
		(lib_id "antmicroLEDIndicationDiscrete:LED_G_0603_LG_L29K-G2J1-24-Z")
		(at 195.58 184.15 90)
		(unit 1)
		(exclude_from_sim no)
		(in_bom yes)
		(on_board yes)
		(dnp no)
		(fields_autoplaced yes)
		(property "Reference" "D8"
			(at 198.12 180.34 90)
			(effects
				(font
					(size 1.27 1.27)
					(thickness 0.15)
				)
				(justify right)
			)
		)
		(property "Value" "LED_G_0603_LG_L29K-G2J1-24-Z"
			(at 203.2 163.83 0)
			(effects
				(font
					(size 1.27 1.27)
					(thickness 0.15)
				)
				(justify left bottom)
				(hide yes)
			)
		)
		(property "Footprint" "antmicro-footprints:LED_0603_1608Metric_G"
			(at 205.74 163.83 0)
			(effects
				(font
					(size 1.27 1.27)
					(thickness 0.15)
				)
				(justify left bottom)
				(hide yes)
			)
		)
		(property "Datasheet" "https://look.ams-osram.com/m/19ee86b3ae0ee95b/original/LG-L29K.pdf"
			(at 208.28 163.83 0)
			(effects
				(font
					(size 1.27 1.27)
					(thickness 0.15)
				)
				(justify left bottom)
				(hide yes)
			)
		)
		(property "Description" "LED, Green, SMD, 0603, 20 mA, 1.7 V, 570 nm"
			(at 195.58 184.15 0)
			(effects
				(font
					(size 1.27 1.27)
				)
				(hide yes)
			)
		)
		(property "MPN" "LG L29K-G2J1-24-Z"
			(at 210.82 163.83 0)
			(effects
				(font
					(size 1.27 1.27)
					(thickness 0.15)
				)
				(justify left bottom)
				(hide yes)
			)
		)
		(property "Manufacturer" "OSRAM"
			(at 213.36 163.83 0)
			(effects
				(font
					(size 1.27 1.27)
					(thickness 0.15)
				)
				(justify left bottom)
				(hide yes)
			)
		)
		(property "Color" "Green"
			(at 198.12 182.8799 90)
			(effects
				(font
					(size 1.27 1.27)
				)
				(justify right)
			)
		)
		(property "Author" "Antmicro"
			(at 215.9 163.83 0)
			(effects
				(font
					(size 1.27 1.27)
					(thickness 0.15)
				)
				(justify left bottom)
				(hide yes)
			)
		)
		(property "License" "Apache-2.0"
			(at 218.44 163.83 0)
			(effects
				(font
					(size 1.27 1.27)
					(thickness 0.15)
				)
				(justify left bottom)
				(hide yes)
			)
		)
		(pin "2"
		)
		(pin "1"
		)
		(instances
			(project "usb-c-power-adapter"
				(path ""
					(reference "D8")
					(unit 1)
				)
			)
		)
	)
	(symbol
		(lib_id "antmicroCapacitorsmisc:C_22u_25V_0805")
		(at 269.24 62.23 90)
		(unit 1)
		(exclude_from_sim no)
		(in_bom yes)
		(on_board yes)
		(dnp no)
		(fields_autoplaced yes)
		(property "Reference" "C17"
			(at 271.78 57.1436 90)
			(effects
				(font
					(size 1.27 1.27)
					(thickness 0.15)
				)
				(justify right)
			)
		)
		(property "Value" "C_22u_25V_0805"
			(at 279.4 41.91 0)
			(effects
				(font
					(size 1.27 1.27)
					(thickness 0.15)
				)
				(justify left bottom)
				(hide yes)
			)
		)
		(property "Footprint" "antmicro-footprints:C_0805_2012Metric"
			(at 281.94 41.91 0)
			(effects
				(font
					(size 1.27 1.27)
					(thickness 0.15)
				)
				(justify left bottom)
				(hide yes)
			)
		)
		(property "Datasheet" "https://product.samsungsem.com/mlcc/CL21A226MAYNNN.do"
			(at 284.48 41.91 0)
			(effects
				(font
					(size 1.27 1.27)
					(thickness 0.15)
				)
				(justify left bottom)
				(hide yes)
			)
		)
		(property "Description" "SMT Multilayer Ceramic Capacitor, 22uF, +/-20%, 25V, X5R, 0805 [2012 Metric]"
			(at 269.24 62.23 0)
			(effects
				(font
					(size 1.27 1.27)
				)
				(hide yes)
			)
		)
		(property "MPN" "CL21A226MAYNNNE"
			(at 287.02 41.91 0)
			(effects
				(font
					(size 1.27 1.27)
					(thickness 0.15)
				)
				(justify left bottom)
				(hide yes)
			)
		)
		(property "Manufacturer" "Samsung Electro-Mechanics"
			(at 289.56 41.91 0)
			(effects
				(font
					(size 1.27 1.27)
					(thickness 0.15)
				)
				(justify left bottom)
				(hide yes)
			)
		)
		(property "License" "Apache-2.0"
			(at 292.1 41.91 0)
			(effects
				(font
					(size 1.27 1.27)
					(thickness 0.15)
				)
				(justify left bottom)
				(hide yes)
			)
		)
		(property "Author" "Antmicro"
			(at 294.64 41.91 0)
			(effects
				(font
					(size 1.27 1.27)
					(thickness 0.15)
				)
				(justify left bottom)
				(hide yes)
			)
		)
		(property "Val" "22u"
			(at 271.78 59.6836 90)
			(effects
				(font
					(size 1.27 1.27)
					(thickness 0.15)
				)
				(justify right)
			)
		)
		(property "Voltage" "25V"
			(at 271.78 62.2235 90)
			(effects
				(font
					(size 1.27 1.27)
				)
				(justify right)
			)
		)
		(property "Dielectric" "X5R"
			(at 299.72 41.91 0)
			(effects
				(font
					(size 1.27 1.27)
				)
				(justify left bottom)
				(hide yes)
			)
		)
		(property "Public" "False"
			(at 302.26 41.91 0)
			(effects
				(font
					(size 1.27 1.27)
				)
				(justify left bottom)
				(hide yes)
			)
		)
		(pin "1"
		)
		(pin "2"
		)
		(instances
			(project "usb-c-power-adapter"
				(path ""
					(reference "C17")
					(unit 1)
				)
			)
		)
	)
	(symbol
		(lib_id "antmicroResistors0402:R_1k_0402")
		(at 128.27 246.38 90)
		(unit 1)
		(exclude_from_sim no)
		(in_bom yes)
		(on_board yes)
		(dnp no)
		(fields_autoplaced yes)
		(property "Reference" "R27"
			(at 130.81 242.57 90)
			(effects
				(font
					(size 1.27 1.27)
					(thickness 0.15)
				)
				(justify right)
			)
		)
		(property "Value" "R_1k_0402"
			(at 140.97 226.06 0)
			(effects
				(font
					(size 1.27 1.27)
					(thickness 0.15)
				)
				(justify left bottom)
				(hide yes)
			)
		)
		(property "Footprint" "antmicro-footprints:R_0402_1005Metric"
			(at 143.51 226.06 0)
			(effects
				(font
					(size 1.27 1.27)
					(thickness 0.15)
				)
				(justify left bottom)
				(hide yes)
			)
		)
		(property "Datasheet" "https://www.bourns.com/docs/product-datasheets/cr.pdf"
			(at 146.05 226.06 0)
			(effects
				(font
					(size 1.27 1.27)
					(thickness 0.15)
				)
				(justify left bottom)
				(hide yes)
			)
		)
		(property "Description" "SMD Chip Resistor, 1 kohm, ± 1%, 63 mW, 0402 [1005 Metric], Thick Film, General Purpose"
			(at 128.27 246.38 0)
			(effects
				(font
					(size 1.27 1.27)
				)
				(hide yes)
			)
		)
		(property "MPN" "CR0402-FX-1001GLF"
			(at 148.59 226.06 0)
			(effects
				(font
					(size 1.27 1.27)
					(thickness 0.15)
				)
				(justify left bottom)
				(hide yes)
			)
		)
		(property "Manufacturer" "Bourns"
			(at 151.13 226.06 0)
			(effects
				(font
					(size 1.27 1.27)
					(thickness 0.15)
				)
				(justify left bottom)
				(hide yes)
			)
		)
		(property "License" "Apache-2.0"
			(at 153.67 226.06 0)
			(effects
				(font
					(size 1.27 1.27)
					(thickness 0.15)
				)
				(justify left bottom)
				(hide yes)
			)
		)
		(property "Author" "Antmicro"
			(at 156.21 226.06 0)
			(effects
				(font
					(size 1.27 1.27)
					(thickness 0.15)
				)
				(justify left bottom)
				(hide yes)
			)
		)
		(property "Val" "1k"
			(at 130.81 245.11 90)
			(effects
				(font
					(size 1.27 1.27)
					(thickness 0.15)
				)
				(justify right)
			)
		)
		(property "Tolerance" "1%"
			(at 138.43 226.06 0)
			(effects
				(font
					(size 1.27 1.27)
				)
				(justify left bottom)
				(hide yes)
			)
		)
		(pin "1"
		)
		(pin "2"
		)
		(instances
			(project "usb-c-power-adapter"
				(path ""
					(reference "R27")
					(unit 1)
				)
			)
		)
	)
	(symbol
		(lib_id "antmicroCapacitors0603:C_10u_25V_0603")
		(at 139.7 181.61 90)
		(unit 1)
		(exclude_from_sim no)
		(in_bom yes)
		(on_board yes)
		(dnp no)
		(fields_autoplaced yes)
		(property "Reference" "C25"
			(at 142.24 177.7936 90)
			(effects
				(font
					(size 1.27 1.27)
					(thickness 0.15)
				)
				(justify right)
			)
		)
		(property "Value" "C_10u_25V_0603"
			(at 149.86 161.29 0)
			(effects
				(font
					(size 1.27 1.27)
					(thickness 0.15)
				)
				(justify left bottom)
				(hide yes)
			)
		)
		(property "Footprint" "antmicro-footprints:C_0603_1608Metric"
			(at 152.4 161.29 0)
			(effects
				(font
					(size 1.27 1.27)
					(thickness 0.15)
				)
				(justify left bottom)
				(hide yes)
			)
		)
		(property "Datasheet" "https://product.tdk.com/en/search/capacitor/ceramic/mlcc/info?part_no=C1608X5R1E106M080AC"
			(at 154.94 161.29 0)
			(effects
				(font
					(size 1.27 1.27)
					(thickness 0.15)
				)
				(justify left bottom)
				(hide yes)
			)
		)
		(property "Description" "SMD Multilayer Ceramic Capacitor, 10 µF, 25 V, 0603 [1608 Metric], ± 20%, X5R, C"
			(at 139.7 181.61 0)
			(effects
				(font
					(size 1.27 1.27)
				)
				(hide yes)
			)
		)
		(property "MPN" "C1608X5R1E106M080AC"
			(at 157.48 161.29 0)
			(effects
				(font
					(size 1.27 1.27)
					(thickness 0.15)
				)
				(justify left bottom)
				(hide yes)
			)
		)
		(property "Manufacturer" "TDK"
			(at 160.02 161.29 0)
			(effects
				(font
					(size 1.27 1.27)
					(thickness 0.15)
				)
				(justify left bottom)
				(hide yes)
			)
		)
		(property "License" "Apache-2.0"
			(at 162.56 161.29 0)
			(effects
				(font
					(size 1.27 1.27)
					(thickness 0.15)
				)
				(justify left bottom)
				(hide yes)
			)
		)
		(property "Author" "Antmicro"
			(at 165.1 161.29 0)
			(effects
				(font
					(size 1.27 1.27)
					(thickness 0.15)
				)
				(justify left bottom)
				(hide yes)
			)
		)
		(property "Val" "10u"
			(at 142.24 180.3336 90)
			(effects
				(font
					(size 1.27 1.27)
					(thickness 0.15)
				)
				(justify right)
			)
		)
		(property "Voltage" "25V"
			(at 167.64 161.29 0)
			(effects
				(font
					(size 1.27 1.27)
				)
				(justify left bottom)
				(hide yes)
			)
		)
		(property "Dielectric" ""
			(at 170.18 161.29 0)
			(effects
				(font
					(size 1.27 1.27)
				)
				(justify left bottom)
				(hide yes)
			)
		)
		(pin "1"
		)
		(pin "2"
		)
		(instances
			(project "usb-c-power-adapter"
				(path ""
					(reference "C25")
					(unit 1)
				)
			)
		)
	)
	(symbol
		(lib_id "antmicroCapacitorsmisc:C_10u_0805_35V")
		(at 87.63 81.28 90)
		(unit 1)
		(exclude_from_sim no)
		(in_bom yes)
		(on_board yes)
		(dnp no)
		(fields_autoplaced yes)
		(property "Reference" "C16"
			(at 90.17 77.4636 90)
			(effects
				(font
					(size 1.27 1.27)
					(thickness 0.15)
				)
				(justify right)
			)
		)
		(property "Value" "C_10u_0805_35V"
			(at 97.79 60.96 0)
			(effects
				(font
					(size 1.27 1.27)
					(thickness 0.15)
				)
				(justify left bottom)
				(hide yes)
			)
		)
		(property "Footprint" "antmicro-footprints:C_0805_2012Metric"
			(at 100.33 60.96 0)
			(effects
				(font
					(size 1.27 1.27)
					(thickness 0.15)
				)
				(justify left bottom)
				(hide yes)
			)
		)
		(property "Datasheet" "https://www.murata.com/products/productdetail?partno=GRM21BR6YA106KE43%23"
			(at 102.87 60.96 0)
			(effects
				(font
					(size 1.27 1.27)
					(thickness 0.15)
				)
				(justify left bottom)
				(hide yes)
			)
		)
		(property "Description" "SMD Multilayer Ceramic Capacitor, 10 µF, 35 V, 0805 [2012 Metric], ± 10%, X5R, GRM Series"
			(at 87.63 81.28 0)
			(effects
				(font
					(size 1.27 1.27)
				)
				(hide yes)
			)
		)
		(property "MPN" "GRM21BR6YA106KE43L"
			(at 105.41 60.96 0)
			(effects
				(font
					(size 1.27 1.27)
					(thickness 0.15)
				)
				(justify left bottom)
				(hide yes)
			)
		)
		(property "Manufacturer" "Murata"
			(at 107.95 60.96 0)
			(effects
				(font
					(size 1.27 1.27)
					(thickness 0.15)
				)
				(justify left bottom)
				(hide yes)
			)
		)
		(property "License" "Apache-2.0"
			(at 110.49 60.96 0)
			(effects
				(font
					(size 1.27 1.27)
					(thickness 0.15)
				)
				(justify left bottom)
				(hide yes)
			)
		)
		(property "Author" "Antmicro"
			(at 113.03 60.96 0)
			(effects
				(font
					(size 1.27 1.27)
					(thickness 0.15)
				)
				(justify left bottom)
				(hide yes)
			)
		)
		(property "Val" "10u"
			(at 90.17 80.0036 90)
			(effects
				(font
					(size 1.27 1.27)
					(thickness 0.15)
				)
				(justify right)
			)
		)
		(property "Voltage" "35V"
			(at 115.57 60.96 0)
			(effects
				(font
					(size 1.27 1.27)
				)
				(justify left bottom)
				(hide yes)
			)
		)
		(property "Dielectric" ""
			(at 118.11 60.96 0)
			(effects
				(font
					(size 1.27 1.27)
				)
				(justify left bottom)
				(hide yes)
			)
		)
		(property "Public" "False"
			(at 120.65 60.96 0)
			(effects
				(font
					(size 1.27 1.27)
				)
				(justify left bottom)
				(hide yes)
			)
		)
		(pin "2"
		)
		(pin "1"
		)
		(instances
			(project "usb-c-power-adapter"
				(path ""
					(reference "C16")
					(unit 1)
				)
			)
		)
	)
	(symbol
		(lib_id "antmicroCapacitors0402:C_1u_25V_0402")
		(at 46.99 113.03 90)
		(unit 1)
		(exclude_from_sim no)
		(in_bom yes)
		(on_board yes)
		(dnp no)
		(fields_autoplaced yes)
		(property "Reference" "C1"
			(at 49.53 109.2136 90)
			(effects
				(font
					(size 1.27 1.27)
					(thickness 0.15)
				)
				(justify right)
			)
		)
		(property "Value" "C_1u_25V_0402"
			(at 57.15 92.71 0)
			(effects
				(font
					(size 1.27 1.27)
					(thickness 0.15)
				)
				(justify left bottom)
				(hide yes)
			)
		)
		(property "Footprint" "antmicro-footprints:C_0402_1005Metric"
			(at 59.69 92.71 0)
			(effects
				(font
					(size 1.27 1.27)
					(thickness 0.15)
				)
				(justify left bottom)
				(hide yes)
			)
		)
		(property "Datasheet" "https://www.murata.com/products/productdetail?partno=GRM155R61E105KE11%23"
			(at 62.23 92.71 0)
			(effects
				(font
					(size 1.27 1.27)
					(thickness 0.15)
				)
				(justify left bottom)
				(hide yes)
			)
		)
		(property "Description" "SMD Multilayer Ceramic Capacitor, 1 µF, 25 V, 0402 [1005 Metric], ± 10%, X5R, GRM Series"
			(at 46.99 113.03 0)
			(effects
				(font
					(size 1.27 1.27)
				)
				(hide yes)
			)
		)
		(property "MPN" "GRM155R61E105KE11J"
			(at 64.77 92.71 0)
			(effects
				(font
					(size 1.27 1.27)
					(thickness 0.15)
				)
				(justify left bottom)
				(hide yes)
			)
		)
		(property "Manufacturer" "Murata"
			(at 67.31 92.71 0)
			(effects
				(font
					(size 1.27 1.27)
					(thickness 0.15)
				)
				(justify left bottom)
				(hide yes)
			)
		)
		(property "License" "Apache-2.0"
			(at 69.85 92.71 0)
			(effects
				(font
					(size 1.27 1.27)
					(thickness 0.15)
				)
				(justify left bottom)
				(hide yes)
			)
		)
		(property "Author" "Antmicro"
			(at 72.39 92.71 0)
			(effects
				(font
					(size 1.27 1.27)
					(thickness 0.15)
				)
				(justify left bottom)
				(hide yes)
			)
		)
		(property "Val" "1u"
			(at 49.53 111.7536 90)
			(effects
				(font
					(size 1.27 1.27)
					(thickness 0.15)
				)
				(justify right)
			)
		)
		(property "Voltage" "25V"
			(at 74.93 92.71 0)
			(effects
				(font
					(size 1.27 1.27)
				)
				(justify left bottom)
				(hide yes)
			)
		)
		(property "Dielectric" "X5R"
			(at 77.47 92.71 0)
			(effects
				(font
					(size 1.27 1.27)
				)
				(justify left bottom)
				(hide yes)
			)
		)
		(pin "2"
		)
		(pin "1"
		)
		(instances
			(project "usb-c-power-adapter"
				(path ""
					(reference "C1")
					(unit 1)
				)
			)
		)
	)
	(symbol
		(lib_id "antmicropower:GND")
		(at 361.95 63.5 0)
		(unit 1)
		(exclude_from_sim no)
		(in_bom yes)
		(on_board yes)
		(dnp no)
		(fields_autoplaced yes)
		(property "Reference" "#PWR059"
			(at 370.84 66.04 0)
			(effects
				(font
					(size 1.27 1.27)
					(thickness 0.15)
				)
				(justify left bottom)
				(hide yes)
			)
		)
		(property "Value" "GND"
			(at 361.95 67.945 0)
			(effects
				(font
					(size 1.27 1.27)
					(thickness 0.15)
				)
			)
		)
		(property "Footprint" ""
			(at 370.84 71.12 0)
			(effects
				(font
					(size 1.27 1.27)
					(thickness 0.15)
				)
				(justify left bottom)
				(hide yes)
			)
		)
		(property "Datasheet" ""
			(at 370.84 76.2 0)
			(effects
				(font
					(size 1.27 1.27)
					(thickness 0.15)
				)
				(justify left bottom)
				(hide yes)
			)
		)
		(property "Description" ""
			(at 361.95 63.5 0)
			(effects
				(font
					(size 1.27 1.27)
				)
				(hide yes)
			)
		)
		(property "Author" "Antmicro"
			(at 370.84 71.12 0)
			(effects
				(font
					(size 1.27 1.27)
					(thickness 0.15)
				)
				(justify left bottom)
				(hide yes)
			)
		)
		(property "License" "Apache-2.0"
			(at 370.84 73.66 0)
			(effects
				(font
					(size 1.27 1.27)
					(thickness 0.15)
				)
				(justify left bottom)
				(hide yes)
			)
		)
		(pin "1"
		)
		(instances
			(project "usb-c-power-adapter"
				(path ""
					(reference "#PWR059")
					(unit 1)
				)
			)
		)
	)
	(symbol
		(lib_id "antmicropower:GND")
		(at 72.39 116.84 0)
		(unit 1)
		(exclude_from_sim no)
		(in_bom yes)
		(on_board yes)
		(dnp no)
		(property "Reference" "#PWR011"
			(at 72.39 116.84 0)
			(effects
				(font
					(size 1.27 1.27)
				)
				(justify left)
				(hide yes)
			)
		)
		(property "Value" "GND"
			(at 72.39 121.285 0)
			(effects
				(font
					(size 1.27 1.27)
				)
			)
		)
		(property "Footprint" ""
			(at 72.39 116.84 0)
			(effects
				(font
					(size 1.27 1.27)
					(thickness 0.15)
				)
				(justify left bottom)
				(hide yes)
			)
		)
		(property "Datasheet" ""
			(at 72.39 116.84 0)
			(effects
				(font
					(size 1.27 1.27)
					(thickness 0.15)
				)
				(justify left bottom)
				(hide yes)
			)
		)
		(property "Description" ""
			(at 72.39 116.84 0)
			(effects
				(font
					(size 1.27 1.27)
				)
				(hide yes)
			)
		)
		(property "Author" "Antmicro"
			(at 81.28 124.46 0)
			(effects
				(font
					(size 1.27 1.27)
					(thickness 0.15)
				)
				(justify left bottom)
				(hide yes)
			)
		)
		(property "License" "Apache-2.0"
			(at 81.28 127 0)
			(effects
				(font
					(size 1.27 1.27)
					(thickness 0.15)
				)
				(justify left bottom)
				(hide yes)
			)
		)
		(pin "1"
		)
		(instances
			(project "usb-c-power-adapter"
				(path ""
					(reference "#PWR011")
					(unit 1)
				)
			)
		)
	)
	(symbol
		(lib_id "antmicroCapacitors0402:C_100n_50V_X8L_0402")
		(at 111.76 233.68 180)
		(unit 1)
		(exclude_from_sim no)
		(in_bom yes)
		(on_board yes)
		(dnp no)
		(property "Reference" "C24"
			(at 108.966 231.14 0)
			(effects
				(font
					(size 1.27 1.27)
					(thickness 0.15)
				)
			)
		)
		(property "Value" "C_100n_50V_X8L_0402"
			(at 96.52 210.82 0)
			(effects
				(font
					(size 1.27 1.27)
					(thickness 0.15)
				)
				(justify left bottom)
				(hide yes)
			)
		)
		(property "Footprint" "antmicro-footprints:C_0402_1005Metric"
			(at 96.52 208.28 0)
			(effects
				(font
					(size 1.27 1.27)
					(thickness 0.15)
				)
				(justify left bottom)
				(hide yes)
			)
		)
		(property "Datasheet" "https://www.murata.com/products/productdetail?partno=GCM155L8EH104KE07%23"
			(at 96.52 205.74 0)
			(effects
				(font
					(size 1.27 1.27)
					(thickness 0.15)
				)
				(justify left bottom)
				(hide yes)
			)
		)
		(property "Description" "SMD Multilayer Ceramic Capacitor, 100nF, 50V, 0402, ±10%, X8L"
			(at 111.76 233.68 0)
			(effects
				(font
					(size 1.27 1.27)
				)
				(hide yes)
			)
		)
		(property "MPN" "GCM155L8EH104KE07D"
			(at 96.52 203.2 0)
			(effects
				(font
					(size 1.27 1.27)
					(thickness 0.15)
				)
				(justify left bottom)
				(hide yes)
			)
		)
		(property "Val" "100n"
			(at 109.22 236.728 0)
			(effects
				(font
					(size 1.27 1.27)
					(thickness 0.15)
				)
			)
		)
		(property "Voltage" "50V"
			(at 96.52 223.52 0)
			(effects
				(font
					(size 1.27 1.27)
					(thickness 0.15)
				)
				(justify left bottom)
				(hide yes)
			)
		)
		(property "Dielectric" "X8L"
			(at 96.52 220.98 0)
			(effects
				(font
					(size 1.27 1.27)
					(thickness 0.15)
				)
				(justify left bottom)
				(hide yes)
			)
		)
		(property "Manufacturer" "Murata"
			(at 96.52 218.44 0)
			(effects
				(font
					(size 1.27 1.27)
					(thickness 0.15)
				)
				(justify left bottom)
				(hide yes)
			)
		)
		(property "License" "Apache-2.0"
			(at 96.52 215.9 0)
			(effects
				(font
					(size 1.27 1.27)
					(thickness 0.15)
				)
				(justify left bottom)
				(hide yes)
			)
		)
		(property "Author" "Antmicro"
			(at 96.52 213.36 0)
			(effects
				(font
					(size 1.27 1.27)
					(thickness 0.15)
				)
				(justify left bottom)
				(hide yes)
			)
		)
		(pin "1"
		)
		(pin "2"
		)
		(instances
			(project "usb-c-power-adapter"
				(path ""
					(reference "C24")
					(unit 1)
				)
			)
		)
	)
	(symbol
		(lib_id "antmicroCapacitorsmisc:C_22u_25V_0805")
		(at 295.91 62.23 90)
		(unit 1)
		(exclude_from_sim no)
		(in_bom yes)
		(on_board yes)
		(dnp no)
		(fields_autoplaced yes)
		(property "Reference" "C35"
			(at 298.45 57.1436 90)
			(effects
				(font
					(size 1.27 1.27)
					(thickness 0.15)
				)
				(justify right)
			)
		)
		(property "Value" "C_22u_25V_0805"
			(at 306.07 41.91 0)
			(effects
				(font
					(size 1.27 1.27)
					(thickness 0.15)
				)
				(justify left bottom)
				(hide yes)
			)
		)
		(property "Footprint" "antmicro-footprints:C_0805_2012Metric"
			(at 308.61 41.91 0)
			(effects
				(font
					(size 1.27 1.27)
					(thickness 0.15)
				)
				(justify left bottom)
				(hide yes)
			)
		)
		(property "Datasheet" "https://product.samsungsem.com/mlcc/CL21A226MAYNNN.do"
			(at 311.15 41.91 0)
			(effects
				(font
					(size 1.27 1.27)
					(thickness 0.15)
				)
				(justify left bottom)
				(hide yes)
			)
		)
		(property "Description" "SMT Multilayer Ceramic Capacitor, 22uF, +/-20%, 25V, X5R, 0805 [2012 Metric]"
			(at 295.91 62.23 0)
			(effects
				(font
					(size 1.27 1.27)
				)
				(hide yes)
			)
		)
		(property "MPN" "CL21A226MAYNNNE"
			(at 313.69 41.91 0)
			(effects
				(font
					(size 1.27 1.27)
					(thickness 0.15)
				)
				(justify left bottom)
				(hide yes)
			)
		)
		(property "Manufacturer" "Samsung Electro-Mechanics"
			(at 316.23 41.91 0)
			(effects
				(font
					(size 1.27 1.27)
					(thickness 0.15)
				)
				(justify left bottom)
				(hide yes)
			)
		)
		(property "License" "Apache-2.0"
			(at 318.77 41.91 0)
			(effects
				(font
					(size 1.27 1.27)
					(thickness 0.15)
				)
				(justify left bottom)
				(hide yes)
			)
		)
		(property "Author" "Antmicro"
			(at 321.31 41.91 0)
			(effects
				(font
					(size 1.27 1.27)
					(thickness 0.15)
				)
				(justify left bottom)
				(hide yes)
			)
		)
		(property "Val" "22u"
			(at 298.45 59.6836 90)
			(effects
				(font
					(size 1.27 1.27)
					(thickness 0.15)
				)
				(justify right)
			)
		)
		(property "Voltage" "25V"
			(at 298.45 62.2235 90)
			(effects
				(font
					(size 1.27 1.27)
				)
				(justify right)
			)
		)
		(property "Dielectric" "X5R"
			(at 326.39 41.91 0)
			(effects
				(font
					(size 1.27 1.27)
				)
				(justify left bottom)
				(hide yes)
			)
		)
		(property "Public" "False"
			(at 328.93 41.91 0)
			(effects
				(font
					(size 1.27 1.27)
				)
				(justify left bottom)
				(hide yes)
			)
		)
		(pin "1"
		)
		(pin "2"
		)
		(instances
			(project "usb-c-power-adapter"
				(path ""
					(reference "C35")
					(unit 1)
				)
			)
		)
	)
	(symbol
		(lib_id "antmicroCapacitorsmisc:C_47u_25V_1206")
		(at 287.02 91.44 90)
		(unit 1)
		(exclude_from_sim no)
		(in_bom yes)
		(on_board yes)
		(dnp no)
		(fields_autoplaced yes)
		(property "Reference" "C34"
			(at 289.56 86.3536 90)
			(effects
				(font
					(size 1.27 1.27)
					(thickness 0.15)
				)
				(justify right)
			)
		)
		(property "Value" "C_47u_25V_1206"
			(at 299.72 76.2 0)
			(effects
				(font
					(size 1.27 1.27)
					(thickness 0.15)
				)
				(justify left bottom)
				(hide yes)
			)
		)
		(property "Footprint" "antmicro-footprints:C_1206_3216Metric"
			(at 302.26 76.2 0)
			(effects
				(font
					(size 1.27 1.27)
					(thickness 0.15)
				)
				(justify left bottom)
				(hide yes)
			)
		)
		(property "Datasheet" "https://product.tdk.com/en/search/capacitor/ceramic/mlcc/info?part_no=C3216X5R1E476M160AC"
			(at 304.8 76.2 0)
			(effects
				(font
					(size 1.27 1.27)
					(thickness 0.15)
				)
				(justify left bottom)
				(hide yes)
			)
		)
		(property "Description" "SMD Multilayer Ceramic Capacitor, 47 µF, 25 V, 1206 [3216 Metric], ± 20%, X5R"
			(at 287.02 91.44 0)
			(effects
				(font
					(size 1.27 1.27)
				)
				(hide yes)
			)
		)
		(property "MPN" "C3216X5R1E476M160AC"
			(at 307.34 76.2 0)
			(effects
				(font
					(size 1.27 1.27)
					(thickness 0.15)
				)
				(justify left bottom)
				(hide yes)
			)
		)
		(property "Val" "47u"
			(at 289.56 88.8936 90)
			(effects
				(font
					(size 1.27 1.27)
					(thickness 0.15)
				)
				(justify right)
			)
		)
		(property "Voltage" "25V"
			(at 289.56 91.4336 90)
			(effects
				(font
					(size 1.27 1.27)
					(thickness 0.15)
				)
				(justify right)
			)
		)
		(property "Author" "Antmicro"
			(at 309.88 76.2 0)
			(effects
				(font
					(size 1.27 1.27)
					(thickness 0.15)
				)
				(justify left bottom)
				(hide yes)
			)
		)
		(property "License" "Apache-2.0"
			(at 312.42 76.2 0)
			(effects
				(font
					(size 1.27 1.27)
					(thickness 0.15)
				)
				(justify left bottom)
				(hide yes)
			)
		)
		(property "Manufacturer" "TDK"
			(at 314.96 76.2 0)
			(effects
				(font
					(size 1.27 1.27)
					(thickness 0.15)
				)
				(justify left bottom)
				(hide yes)
			)
		)
		(property "Dielectric" "X5R"
			(at 317.5 76.2 0)
			(effects
				(font
					(size 1.27 1.27)
					(thickness 0.15)
				)
				(justify left bottom)
				(hide yes)
			)
		)
		(property "Public" "False"
			(at 320.04 71.12 0)
			(effects
				(font
					(size 1.27 1.27)
				)
				(justify left bottom)
				(hide yes)
			)
		)
		(pin "2"
		)
		(pin "1"
		)
		(instances
			(project "usb-c-power-adapter"
				(path ""
					(reference "C34")
					(unit 1)
				)
			)
		)
	)
	(symbol
		(lib_id "antmicroCapacitors0603:C_10u_25V_0603")
		(at 50.8 182.88 90)
		(unit 1)
		(exclude_from_sim no)
		(in_bom yes)
		(on_board yes)
		(dnp no)
		(fields_autoplaced yes)
		(property "Reference" "C21"
			(at 53.34 179.0636 90)
			(effects
				(font
					(size 1.27 1.27)
					(thickness 0.15)
				)
				(justify right)
			)
		)
		(property "Value" "C_10u_25V_0603"
			(at 60.96 162.56 0)
			(effects
				(font
					(size 1.27 1.27)
					(thickness 0.15)
				)
				(justify left bottom)
				(hide yes)
			)
		)
		(property "Footprint" "antmicro-footprints:C_0603_1608Metric"
			(at 63.5 162.56 0)
			(effects
				(font
					(size 1.27 1.27)
					(thickness 0.15)
				)
				(justify left bottom)
				(hide yes)
			)
		)
		(property "Datasheet" "https://product.tdk.com/en/search/capacitor/ceramic/mlcc/info?part_no=C1608X5R1E106M080AC"
			(at 66.04 162.56 0)
			(effects
				(font
					(size 1.27 1.27)
					(thickness 0.15)
				)
				(justify left bottom)
				(hide yes)
			)
		)
		(property "Description" "SMD Multilayer Ceramic Capacitor, 10 µF, 25 V, 0603 [1608 Metric], ± 20%, X5R, C"
			(at 50.8 182.88 0)
			(effects
				(font
					(size 1.27 1.27)
				)
				(hide yes)
			)
		)
		(property "MPN" "C1608X5R1E106M080AC"
			(at 68.58 162.56 0)
			(effects
				(font
					(size 1.27 1.27)
					(thickness 0.15)
				)
				(justify left bottom)
				(hide yes)
			)
		)
		(property "Manufacturer" "TDK"
			(at 71.12 162.56 0)
			(effects
				(font
					(size 1.27 1.27)
					(thickness 0.15)
				)
				(justify left bottom)
				(hide yes)
			)
		)
		(property "License" "Apache-2.0"
			(at 73.66 162.56 0)
			(effects
				(font
					(size 1.27 1.27)
					(thickness 0.15)
				)
				(justify left bottom)
				(hide yes)
			)
		)
		(property "Author" "Antmicro"
			(at 76.2 162.56 0)
			(effects
				(font
					(size 1.27 1.27)
					(thickness 0.15)
				)
				(justify left bottom)
				(hide yes)
			)
		)
		(property "Val" "10u"
			(at 53.34 181.6036 90)
			(effects
				(font
					(size 1.27 1.27)
					(thickness 0.15)
				)
				(justify right)
			)
		)
		(property "Voltage" "25V"
			(at 78.74 162.56 0)
			(effects
				(font
					(size 1.27 1.27)
				)
				(justify left bottom)
				(hide yes)
			)
		)
		(property "Dielectric" ""
			(at 81.28 162.56 0)
			(effects
				(font
					(size 1.27 1.27)
				)
				(justify left bottom)
				(hide yes)
			)
		)
		(pin "1"
		)
		(pin "2"
		)
		(instances
			(project "usb-c-power-adapter"
				(path ""
					(reference "C21")
					(unit 1)
				)
			)
		)
	)
	(symbol
		(lib_id "antmicropower:+3V3")
		(at 382.27 95.25 0)
		(unit 1)
		(exclude_from_sim no)
		(in_bom yes)
		(on_board yes)
		(dnp no)
		(fields_autoplaced yes)
		(property "Reference" "#PWR030"
			(at 397.51 95.25 0)
			(effects
				(font
					(size 1.27 1.27)
					(thickness 0.15)
				)
				(justify left bottom)
				(hide yes)
			)
		)
		(property "Value" "+3V3"
			(at 382.27 90.17 0)
			(effects
				(font
					(size 1.27 1.27)
					(thickness 0.15)
				)
			)
		)
		(property "Footprint" ""
			(at 397.51 102.87 0)
			(effects
				(font
					(size 1.27 1.27)
					(thickness 0.15)
				)
				(justify left bottom)
				(hide yes)
			)
		)
		(property "Datasheet" ""
			(at 397.51 105.41 0)
			(effects
				(font
					(size 1.27 1.27)
					(thickness 0.15)
				)
				(justify left bottom)
				(hide yes)
			)
		)
		(property "Description" ""
			(at 382.27 95.25 0)
			(effects
				(font
					(size 1.27 1.27)
				)
				(hide yes)
			)
		)
		(property "Author" "Antmicro"
			(at 397.51 97.79 0)
			(effects
				(font
					(size 1.27 1.27)
					(thickness 0.15)
				)
				(justify left bottom)
				(hide yes)
			)
		)
		(property "License" "Apache-2.0"
			(at 397.51 100.33 0)
			(effects
				(font
					(size 1.27 1.27)
					(thickness 0.15)
				)
				(justify left bottom)
				(hide yes)
			)
		)
		(pin "1"
		)
		(instances
			(project "usb-c-power-adapter"
				(path ""
					(reference "#PWR030")
					(unit 1)
				)
			)
		)
	)
	(symbol
		(lib_id "antmicropower:+12V")
		(at 269.24 68.58 0)
		(unit 1)
		(exclude_from_sim no)
		(in_bom yes)
		(on_board yes)
		(dnp no)
		(property "Reference" "#PWR015"
			(at 269.24 72.39 0)
			(effects
				(font
					(size 1.27 1.27)
				)
				(hide yes)
			)
		)
		(property "Value" "+12V"
			(at 265.43 66.04 0)
			(effects
				(font
					(size 1.27 1.27)
				)
			)
		)
		(property "Footprint" ""
			(at 269.24 68.58 0)
			(effects
				(font
					(size 1.27 1.27)
				)
				(hide yes)
			)
		)
		(property "Datasheet" ""
			(at 269.24 68.58 0)
			(effects
				(font
					(size 1.27 1.27)
				)
				(hide yes)
			)
		)
		(property "Description" ""
			(at 269.24 68.58 0)
			(effects
				(font
					(size 1.27 1.27)
				)
				(hide yes)
			)
		)
		(pin "1"
		)
		(instances
			(project "usb-c-power-adapter"
				(path ""
					(reference "#PWR015")
					(unit 1)
				)
			)
		)
	)
	(symbol
		(lib_id "antmicropower:GND")
		(at 69.85 82.55 0)
		(unit 1)
		(exclude_from_sim no)
		(in_bom yes)
		(on_board yes)
		(dnp no)
		(property "Reference" "#PWR08"
			(at 69.85 82.55 0)
			(effects
				(font
					(size 1.27 1.27)
				)
				(justify left)
				(hide yes)
			)
		)
		(property "Value" "GND"
			(at 69.85 86.36 0)
			(effects
				(font
					(size 1.27 1.27)
				)
			)
		)
		(property "Footprint" ""
			(at 69.85 82.55 0)
			(effects
				(font
					(size 1.27 1.27)
					(thickness 0.15)
				)
				(justify left bottom)
				(hide yes)
			)
		)
		(property "Datasheet" ""
			(at 69.85 82.55 0)
			(effects
				(font
					(size 1.27 1.27)
					(thickness 0.15)
				)
				(justify left bottom)
				(hide yes)
			)
		)
		(property "Description" ""
			(at 69.85 82.55 0)
			(effects
				(font
					(size 1.27 1.27)
				)
				(hide yes)
			)
		)
		(property "Author" "Antmicro"
			(at 78.74 90.17 0)
			(effects
				(font
					(size 1.27 1.27)
					(thickness 0.15)
				)
				(justify left bottom)
				(hide yes)
			)
		)
		(property "License" "Apache-2.0"
			(at 78.74 92.71 0)
			(effects
				(font
					(size 1.27 1.27)
					(thickness 0.15)
				)
				(justify left bottom)
				(hide yes)
			)
		)
		(pin "1"
		)
		(instances
			(project "usb-c-power-adapter"
				(path ""
					(reference "#PWR08")
					(unit 1)
				)
			)
		)
	)
	(symbol
		(lib_id "antmicroResistors0402:R_316k_0402")
		(at 177.8 96.52 90)
		(mirror x)
		(unit 1)
		(exclude_from_sim no)
		(in_bom no)
		(on_board yes)
		(dnp yes)
		(fields_autoplaced yes)
		(property "Reference" "R16"
			(at 180.34 97.7899 90)
			(effects
				(font
					(size 1.27 1.27)
				)
				(justify right)
			)
		)
		(property "Value" "R_316k_0402"
			(at 181.61 96.52 0)
			(effects
				(font
					(size 1.27 1.27)
				)
				(justify left)
				(hide yes)
			)
		)
		(property "Footprint" "antmicro-footprints:R_0402_1005Metric"
			(at 172.72 101.6 0)
			(effects
				(font
					(size 1.27 1.27)
					(thickness 0.15)
				)
				(justify left bottom)
				(hide yes)
			)
		)
		(property "Datasheet" "https://www.bourns.com/docs/product-datasheets/cr.pdf"
			(at 177.8 96.52 0)
			(effects
				(font
					(size 1.27 1.27)
					(thickness 0.15)
				)
				(justify left bottom)
				(hide yes)
			)
		)
		(property "Description" "SMD Chip Resistor"
			(at 177.8 96.52 0)
			(effects
				(font
					(size 1.27 1.27)
				)
				(hide yes)
			)
		)
		(property "Manufacturer" "Bourns"
			(at 167.64 101.6 0)
			(effects
				(font
					(size 1.27 1.27)
					(thickness 0.15)
				)
				(justify left bottom)
				(hide yes)
			)
		)
		(property "MPN" "CR0402-FX-3163GLF"
			(at 170.18 101.6 0)
			(effects
				(font
					(size 1.27 1.27)
					(thickness 0.15)
				)
				(justify left bottom)
				(hide yes)
			)
		)
		(property "Val" "316k"
			(at 180.34 100.33 90)
			(effects
				(font
					(size 1.27 1.27)
					(thickness 0.15)
				)
				(justify right)
			)
		)
		(property "License" "Apache-2.0"
			(at 203.2 116.84 0)
			(effects
				(font
					(size 1.27 1.27)
					(thickness 0.15)
				)
				(justify left bottom)
				(hide yes)
			)
		)
		(property "Author" "Antmicro"
			(at 205.74 116.84 0)
			(effects
				(font
					(size 1.27 1.27)
					(thickness 0.15)
				)
				(justify left bottom)
				(hide yes)
			)
		)
		(property "Tolerance" "1%"
			(at 187.96 116.84 0)
			(effects
				(font
					(size 1.27 1.27)
				)
				(justify left bottom)
				(hide yes)
			)
		)
		(pin "1"
		)
		(pin "2"
		)
		(instances
			(project "usb-c-power-adapter"
				(path ""
					(reference "R16")
					(unit 1)
				)
			)
		)
	)
	(symbol
		(lib_id "antmicropower:PWR_FLAG")
		(at 135.89 224.79 0)
		(unit 1)
		(exclude_from_sim no)
		(in_bom yes)
		(on_board yes)
		(dnp no)
		(fields_autoplaced yes)
		(property "Reference" "#FLG08"
			(at 135.89 222.885 0)
			(effects
				(font
					(size 1.27 1.27)
				)
				(hide yes)
			)
		)
		(property "Value" "PWR_FLAG"
			(at 135.89 219.71 0)
			(effects
				(font
					(size 1.27 1.27)
				)
			)
		)
		(property "Footprint" ""
			(at 135.89 224.79 0)
			(effects
				(font
					(size 1.27 1.27)
				)
				(hide yes)
			)
		)
		(property "Datasheet" ""
			(at 135.89 224.79 0)
			(effects
				(font
					(size 1.27 1.27)
				)
				(hide yes)
			)
		)
		(property "Description" ""
			(at 135.89 224.79 0)
			(effects
				(font
					(size 1.27 1.27)
				)
				(hide yes)
			)
		)
		(pin "1"
		)
		(instances
			(project "usb-c-power-adapter"
				(path ""
					(reference "#FLG08")
					(unit 1)
				)
			)
		)
	)
	(symbol
		(lib_id "antmicroCapacitorsmisc:C_22u_25V_0805")
		(at 287.02 62.23 90)
		(unit 1)
		(exclude_from_sim no)
		(in_bom yes)
		(on_board yes)
		(dnp no)
		(fields_autoplaced yes)
		(property "Reference" "C32"
			(at 289.56 57.1436 90)
			(effects
				(font
					(size 1.27 1.27)
					(thickness 0.15)
				)
				(justify right)
			)
		)
		(property "Value" "C_22u_25V_0805"
			(at 297.18 41.91 0)
			(effects
				(font
					(size 1.27 1.27)
					(thickness 0.15)
				)
				(justify left bottom)
				(hide yes)
			)
		)
		(property "Footprint" "antmicro-footprints:C_0805_2012Metric"
			(at 299.72 41.91 0)
			(effects
				(font
					(size 1.27 1.27)
					(thickness 0.15)
				)
				(justify left bottom)
				(hide yes)
			)
		)
		(property "Datasheet" "https://product.samsungsem.com/mlcc/CL21A226MAYNNN.do"
			(at 302.26 41.91 0)
			(effects
				(font
					(size 1.27 1.27)
					(thickness 0.15)
				)
				(justify left bottom)
				(hide yes)
			)
		)
		(property "Description" "SMT Multilayer Ceramic Capacitor, 22uF, +/-20%, 25V, X5R, 0805 [2012 Metric]"
			(at 287.02 62.23 0)
			(effects
				(font
					(size 1.27 1.27)
				)
				(hide yes)
			)
		)
		(property "MPN" "CL21A226MAYNNNE"
			(at 304.8 41.91 0)
			(effects
				(font
					(size 1.27 1.27)
					(thickness 0.15)
				)
				(justify left bottom)
				(hide yes)
			)
		)
		(property "Manufacturer" "Samsung Electro-Mechanics"
			(at 307.34 41.91 0)
			(effects
				(font
					(size 1.27 1.27)
					(thickness 0.15)
				)
				(justify left bottom)
				(hide yes)
			)
		)
		(property "License" "Apache-2.0"
			(at 309.88 41.91 0)
			(effects
				(font
					(size 1.27 1.27)
					(thickness 0.15)
				)
				(justify left bottom)
				(hide yes)
			)
		)
		(property "Author" "Antmicro"
			(at 312.42 41.91 0)
			(effects
				(font
					(size 1.27 1.27)
					(thickness 0.15)
				)
				(justify left bottom)
				(hide yes)
			)
		)
		(property "Val" "22u"
			(at 289.56 59.6836 90)
			(effects
				(font
					(size 1.27 1.27)
					(thickness 0.15)
				)
				(justify right)
			)
		)
		(property "Voltage" "25V"
			(at 289.56 62.2235 90)
			(effects
				(font
					(size 1.27 1.27)
				)
				(justify right)
			)
		)
		(property "Dielectric" "X5R"
			(at 317.5 41.91 0)
			(effects
				(font
					(size 1.27 1.27)
				)
				(justify left bottom)
				(hide yes)
			)
		)
		(property "Public" "False"
			(at 320.04 41.91 0)
			(effects
				(font
					(size 1.27 1.27)
				)
				(justify left bottom)
				(hide yes)
			)
		)
		(pin "1"
		)
		(pin "2"
		)
		(instances
			(project "usb-c-power-adapter"
				(path ""
					(reference "C32")
					(unit 1)
				)
			)
		)
	)
	(symbol
		(lib_id "antmicropower:GND")
		(at 49.53 82.55 0)
		(unit 1)
		(exclude_from_sim no)
		(in_bom yes)
		(on_board yes)
		(dnp no)
		(property "Reference" "#PWR091"
			(at 49.53 82.55 0)
			(effects
				(font
					(size 1.27 1.27)
				)
				(justify left)
				(hide yes)
			)
		)
		(property "Value" "GND"
			(at 49.53 86.36 0)
			(effects
				(font
					(size 1.27 1.27)
				)
			)
		)
		(property "Footprint" ""
			(at 49.53 82.55 0)
			(effects
				(font
					(size 1.27 1.27)
					(thickness 0.15)
				)
				(justify left bottom)
				(hide yes)
			)
		)
		(property "Datasheet" ""
			(at 49.53 82.55 0)
			(effects
				(font
					(size 1.27 1.27)
					(thickness 0.15)
				)
				(justify left bottom)
				(hide yes)
			)
		)
		(property "Description" ""
			(at 49.53 82.55 0)
			(effects
				(font
					(size 1.27 1.27)
				)
				(hide yes)
			)
		)
		(property "Author" "Antmicro"
			(at 58.42 90.17 0)
			(effects
				(font
					(size 1.27 1.27)
					(thickness 0.15)
				)
				(justify left bottom)
				(hide yes)
			)
		)
		(property "License" "Apache-2.0"
			(at 58.42 92.71 0)
			(effects
				(font
					(size 1.27 1.27)
					(thickness 0.15)
				)
				(justify left bottom)
				(hide yes)
			)
		)
		(pin "1"
		)
		(instances
			(project "usb-c-power-adapter"
				(path ""
					(reference "#PWR091")
					(unit 1)
				)
			)
		)
	)
	(symbol
		(lib_id "antmicroResistors0402:R_3R3_0402")
		(at 152.4 73.66 0)
		(mirror x)
		(unit 1)
		(exclude_from_sim no)
		(in_bom yes)
		(on_board yes)
		(dnp no)
		(fields_autoplaced yes)
		(property "Reference" "R14"
			(at 154.94 67.31 0)
			(effects
				(font
					(size 1.27 1.27)
				)
			)
		)
		(property "Value" "R_3R3_0402"
			(at 152.4 69.85 0)
			(effects
				(font
					(size 1.27 1.27)
				)
				(justify left)
				(hide yes)
			)
		)
		(property "Footprint" "antmicro-footprints:R_0402_1005Metric"
			(at 157.48 78.74 0)
			(effects
				(font
					(size 1.27 1.27)
					(thickness 0.15)
				)
				(justify left bottom)
				(hide yes)
			)
		)
		(property "Datasheet" "https://www.bourns.com/docs/product-datasheets/cr.pdf"
			(at 152.4 73.66 0)
			(effects
				(font
					(size 1.27 1.27)
					(thickness 0.15)
				)
				(justify left bottom)
				(hide yes)
			)
		)
		(property "Description" "SMD Chip Resistor, 3.3 ohm, ± 1%, 62.5 mW, 0402 [1005 Metric], Thick Film, General Purpose"
			(at 152.4 73.66 0)
			(effects
				(font
					(size 1.27 1.27)
				)
				(hide yes)
			)
		)
		(property "Manufacturer" "Bourns"
			(at 157.48 83.82 0)
			(effects
				(font
					(size 1.27 1.27)
					(thickness 0.15)
				)
				(justify left bottom)
				(hide yes)
			)
		)
		(property "MPN" "CR0402-FX-3R30GLF"
			(at 157.48 81.28 0)
			(effects
				(font
					(size 1.27 1.27)
					(thickness 0.15)
				)
				(justify left bottom)
				(hide yes)
			)
		)
		(property "Val" "3R3"
			(at 154.94 69.85 0)
			(effects
				(font
					(size 1.27 1.27)
					(thickness 0.15)
				)
			)
		)
		(property "License" "Apache-2.0"
			(at 172.72 48.26 0)
			(effects
				(font
					(size 1.27 1.27)
					(thickness 0.15)
				)
				(justify left bottom)
				(hide yes)
			)
		)
		(property "Author" "Antmicro"
			(at 172.72 45.72 0)
			(effects
				(font
					(size 1.27 1.27)
					(thickness 0.15)
				)
				(justify left bottom)
				(hide yes)
			)
		)
		(property "Tolerance" "1%"
			(at 172.72 63.5 0)
			(effects
				(font
					(size 1.27 1.27)
				)
				(justify left bottom)
				(hide yes)
			)
		)
		(pin "1"
		)
		(pin "2"
		)
		(instances
			(project "usb-c-power-adapter"
				(path ""
					(reference "R14")
					(unit 1)
				)
			)
		)
	)
	(symbol
		(lib_id "antmicroResistors0402:R_15k_0402")
		(at 71.12 245.11 90)
		(unit 1)
		(exclude_from_sim no)
		(in_bom yes)
		(on_board yes)
		(dnp no)
		(fields_autoplaced yes)
		(property "Reference" "R24"
			(at 73.66 241.3 90)
			(effects
				(font
					(size 1.27 1.27)
					(thickness 0.15)
				)
				(justify right)
			)
		)
		(property "Value" "R_15k_0402"
			(at 83.82 224.79 0)
			(effects
				(font
					(size 1.27 1.27)
					(thickness 0.15)
				)
				(justify left bottom)
				(hide yes)
			)
		)
		(property "Footprint" "antmicro-footprints:R_0402_1005Metric"
			(at 86.36 224.79 0)
			(effects
				(font
					(size 1.27 1.27)
					(thickness 0.15)
				)
				(justify left bottom)
				(hide yes)
			)
		)
		(property "Datasheet" "https://www.bourns.com/docs/product-datasheets/cr.pdf"
			(at 88.9 224.79 0)
			(effects
				(font
					(size 1.27 1.27)
					(thickness 0.15)
				)
				(justify left bottom)
				(hide yes)
			)
		)
		(property "Description" "SMD Chip Resistor, 15 kohm, ± 1%, 62.5 mW, 0402 [1005 Metric], Thick Film, General Purpose"
			(at 71.12 245.11 0)
			(effects
				(font
					(size 1.27 1.27)
				)
				(hide yes)
			)
		)
		(property "MPN" "CR0402-FX-1502GLF"
			(at 91.44 224.79 0)
			(effects
				(font
					(size 1.27 1.27)
					(thickness 0.15)
				)
				(justify left bottom)
				(hide yes)
			)
		)
		(property "Manufacturer" "Bourns"
			(at 93.98 224.79 0)
			(effects
				(font
					(size 1.27 1.27)
					(thickness 0.15)
				)
				(justify left bottom)
				(hide yes)
			)
		)
		(property "License" "Apache-2.0"
			(at 96.52 224.79 0)
			(effects
				(font
					(size 1.27 1.27)
					(thickness 0.15)
				)
				(justify left bottom)
				(hide yes)
			)
		)
		(property "Author" "Antmicro"
			(at 99.06 224.79 0)
			(effects
				(font
					(size 1.27 1.27)
					(thickness 0.15)
				)
				(justify left bottom)
				(hide yes)
			)
		)
		(property "Val" "15k"
			(at 73.66 243.84 90)
			(effects
				(font
					(size 1.27 1.27)
					(thickness 0.15)
				)
				(justify right)
			)
		)
		(property "Tolerance" "1%"
			(at 81.28 224.79 0)
			(effects
				(font
					(size 1.27 1.27)
				)
				(justify left bottom)
				(hide yes)
			)
		)
		(pin "1"
		)
		(pin "2"
		)
		(instances
			(project "usb-c-power-adapter"
				(path ""
					(reference "R24")
					(unit 1)
				)
			)
		)
	)
	(symbol
		(lib_id "antmicropower:GND")
		(at 87.63 82.55 0)
		(unit 1)
		(exclude_from_sim no)
		(in_bom yes)
		(on_board yes)
		(dnp no)
		(property "Reference" "#PWR089"
			(at 87.63 82.55 0)
			(effects
				(font
					(size 1.27 1.27)
				)
				(justify left)
				(hide yes)
			)
		)
		(property "Value" "GND"
			(at 87.63 86.36 0)
			(effects
				(font
					(size 1.27 1.27)
				)
			)
		)
		(property "Footprint" ""
			(at 87.63 82.55 0)
			(effects
				(font
					(size 1.27 1.27)
					(thickness 0.15)
				)
				(justify left bottom)
				(hide yes)
			)
		)
		(property "Datasheet" ""
			(at 87.63 82.55 0)
			(effects
				(font
					(size 1.27 1.27)
					(thickness 0.15)
				)
				(justify left bottom)
				(hide yes)
			)
		)
		(property "Description" ""
			(at 87.63 82.55 0)
			(effects
				(font
					(size 1.27 1.27)
				)
				(hide yes)
			)
		)
		(property "Author" "Antmicro"
			(at 96.52 90.17 0)
			(effects
				(font
					(size 1.27 1.27)
					(thickness 0.15)
				)
				(justify left bottom)
				(hide yes)
			)
		)
		(property "License" "Apache-2.0"
			(at 96.52 92.71 0)
			(effects
				(font
					(size 1.27 1.27)
					(thickness 0.15)
				)
				(justify left bottom)
				(hide yes)
			)
		)
		(pin "1"
		)
		(instances
			(project "usb-c-power-adapter"
				(path ""
					(reference "#PWR089")
					(unit 1)
				)
			)
		)
	)
	(symbol
		(lib_id "antmicroResistors0402:R_100k_0402")
		(at 68.58 233.68 180)
		(unit 1)
		(exclude_from_sim no)
		(in_bom yes)
		(on_board yes)
		(dnp no)
		(property "Reference" "R11"
			(at 66.04 235.966 0)
			(effects
				(font
					(size 1.27 1.27)
					(thickness 0.15)
				)
			)
		)
		(property "Value" "R_100k_0402"
			(at 48.26 220.98 0)
			(effects
				(font
					(size 1.27 1.27)
					(thickness 0.15)
				)
				(justify left bottom)
				(hide yes)
			)
		)
		(property "Footprint" "antmicro-footprints:R_0402_1005Metric"
			(at 48.26 218.44 0)
			(effects
				(font
					(size 1.27 1.27)
					(thickness 0.15)
				)
				(justify left bottom)
				(hide yes)
			)
		)
		(property "Datasheet" "https://www.bourns.com/docs/product-datasheets/cr.pdf"
			(at 48.26 215.9 0)
			(effects
				(font
					(size 1.27 1.27)
					(thickness 0.15)
				)
				(justify left bottom)
				(hide yes)
			)
		)
		(property "Description" "SMD Chip Resistor, 100 kohm, ± 1%, 62.5 mW, 0402 [1005 Metric], Thick Film, General Purpose"
			(at 68.58 233.68 0)
			(effects
				(font
					(size 1.27 1.27)
				)
				(hide yes)
			)
		)
		(property "MPN" "CR0402-FX-1003GLF"
			(at 48.26 213.36 0)
			(effects
				(font
					(size 1.27 1.27)
					(thickness 0.15)
				)
				(justify left bottom)
				(hide yes)
			)
		)
		(property "Manufacturer" "Bourns"
			(at 48.26 210.82 0)
			(effects
				(font
					(size 1.27 1.27)
					(thickness 0.15)
				)
				(justify left bottom)
				(hide yes)
			)
		)
		(property "License" "Apache-2.0"
			(at 48.26 208.28 0)
			(effects
				(font
					(size 1.27 1.27)
					(thickness 0.15)
				)
				(justify left bottom)
				(hide yes)
			)
		)
		(property "Author" "Antmicro"
			(at 48.26 205.74 0)
			(effects
				(font
					(size 1.27 1.27)
					(thickness 0.15)
				)
				(justify left bottom)
				(hide yes)
			)
		)
		(property "Val" "100k"
			(at 66.04 238.506 0)
			(effects
				(font
					(size 1.27 1.27)
					(thickness 0.15)
				)
			)
		)
		(property "Tolerance" "1%"
			(at 48.26 223.52 0)
			(effects
				(font
					(size 1.27 1.27)
				)
				(justify left bottom)
				(hide yes)
			)
		)
		(pin "1"
		)
		(pin "2"
		)
		(instances
			(project "usb-c-power-adapter"
				(path ""
					(reference "R11")
					(unit 1)
				)
			)
		)
	)
	(symbol
		(lib_id "antmicroTestPoints:TP_0.75mm_SMD")
		(at 146.05 226.06 90)
		(unit 1)
		(exclude_from_sim no)
		(in_bom no)
		(on_board yes)
		(dnp no)
		(property "Reference" "TP6"
			(at 144.78 219.71 90)
			(effects
				(font
					(size 1.27 1.27)
					(thickness 0.15)
				)
				(justify right)
			)
		)
		(property "Value" "TP_0.75mm_SMD"
			(at 149.86 215.265 0)
			(effects
				(font
					(size 1.27 1.27)
					(thickness 0.15)
				)
				(justify left bottom)
				(hide yes)
			)
		)
		(property "Footprint" "antmicro-footprints:TP_SMD_0.75mm"
			(at 152.4 215.265 0)
			(effects
				(font
					(size 1.27 1.27)
					(thickness 0.15)
				)
				(justify left bottom)
				(hide yes)
			)
		)
		(property "Datasheet" ""
			(at 158.75 208.28 0)
			(effects
				(font
					(size 1.27 1.27)
					(thickness 0.15)
				)
				(justify left bottom)
				(hide yes)
			)
		)
		(property "Description" "SMT test point"
			(at 146.05 226.06 0)
			(effects
				(font
					(size 1.27 1.27)
				)
				(hide yes)
			)
		)
		(property "MPN" ""
			(at 157.48 215.265 0)
			(effects
				(font
					(size 1.27 1.27)
					(thickness 0.15)
				)
				(justify left bottom)
				(hide yes)
			)
		)
		(property "Manufacturer" ""
			(at 152.4 215.265 0)
			(effects
				(font
					(size 1.27 1.27)
					(thickness 0.15)
				)
				(justify left bottom)
				(hide yes)
			)
		)
		(property "Author" "Antmicro"
			(at 154.94 215.265 0)
			(effects
				(font
					(size 1.27 1.27)
					(thickness 0.15)
				)
				(justify left bottom)
				(hide yes)
			)
		)
		(property "License" "Apache-2.0"
			(at 157.48 215.265 0)
			(effects
				(font
					(size 1.27 1.27)
					(thickness 0.15)
				)
				(justify left bottom)
				(hide yes)
			)
		)
		(pin "1"
		)
		(instances
			(project "usb-c-power-adapter"
				(path ""
					(reference "TP6")
					(unit 1)
				)
			)
		)
	)
	(symbol
		(lib_id "antmicropower:+12V")
		(at 269.24 54.61 0)
		(unit 1)
		(exclude_from_sim no)
		(in_bom yes)
		(on_board yes)
		(dnp no)
		(property "Reference" "#PWR09"
			(at 269.24 58.42 0)
			(effects
				(font
					(size 1.27 1.27)
				)
				(hide yes)
			)
		)
		(property "Value" "+12V"
			(at 265.43 52.07 0)
			(effects
				(font
					(size 1.27 1.27)
				)
			)
		)
		(property "Footprint" ""
			(at 269.24 54.61 0)
			(effects
				(font
					(size 1.27 1.27)
				)
				(hide yes)
			)
		)
		(property "Datasheet" ""
			(at 269.24 54.61 0)
			(effects
				(font
					(size 1.27 1.27)
				)
				(hide yes)
			)
		)
		(property "Description" ""
			(at 269.24 54.61 0)
			(effects
				(font
					(size 1.27 1.27)
				)
				(hide yes)
			)
		)
		(pin "1"
		)
		(instances
			(project "usb-c-power-adapter"
				(path ""
					(reference "#PWR09")
					(unit 1)
				)
			)
		)
	)
	(symbol
		(lib_id "antmicroCapacitors0402:C_1u_25V_0402")
		(at 369.57 59.69 90)
		(unit 1)
		(exclude_from_sim no)
		(in_bom yes)
		(on_board yes)
		(dnp no)
		(fields_autoplaced yes)
		(property "Reference" "C40"
			(at 372.11 55.8736 90)
			(effects
				(font
					(size 1.27 1.27)
					(thickness 0.15)
				)
				(justify right)
			)
		)
		(property "Value" "C_1u_25V_0402"
			(at 379.73 39.37 0)
			(effects
				(font
					(size 1.27 1.27)
					(thickness 0.15)
				)
				(justify left bottom)
				(hide yes)
			)
		)
		(property "Footprint" "antmicro-footprints:C_0402_1005Metric"
			(at 382.27 39.37 0)
			(effects
				(font
					(size 1.27 1.27)
					(thickness 0.15)
				)
				(justify left bottom)
				(hide yes)
			)
		)
		(property "Datasheet" "https://www.murata.com/products/productdetail?partno=GRM155R61E105KE11%23"
			(at 384.81 39.37 0)
			(effects
				(font
					(size 1.27 1.27)
					(thickness 0.15)
				)
				(justify left bottom)
				(hide yes)
			)
		)
		(property "Description" "SMD Multilayer Ceramic Capacitor, 1 µF, 25 V, 0402 [1005 Metric], ± 10%, X5R, GRM Series"
			(at 369.57 59.69 0)
			(effects
				(font
					(size 1.27 1.27)
				)
				(hide yes)
			)
		)
		(property "MPN" "GRM155R61E105KE11J"
			(at 387.35 39.37 0)
			(effects
				(font
					(size 1.27 1.27)
					(thickness 0.15)
				)
				(justify left bottom)
				(hide yes)
			)
		)
		(property "Manufacturer" "Murata"
			(at 389.89 39.37 0)
			(effects
				(font
					(size 1.27 1.27)
					(thickness 0.15)
				)
				(justify left bottom)
				(hide yes)
			)
		)
		(property "License" "Apache-2.0"
			(at 392.43 39.37 0)
			(effects
				(font
					(size 1.27 1.27)
					(thickness 0.15)
				)
				(justify left bottom)
				(hide yes)
			)
		)
		(property "Author" "Antmicro"
			(at 394.97 39.37 0)
			(effects
				(font
					(size 1.27 1.27)
					(thickness 0.15)
				)
				(justify left bottom)
				(hide yes)
			)
		)
		(property "Val" "1u"
			(at 372.11 58.4136 90)
			(effects
				(font
					(size 1.27 1.27)
					(thickness 0.15)
				)
				(justify right)
			)
		)
		(property "Voltage" "25V"
			(at 397.51 39.37 0)
			(effects
				(font
					(size 1.27 1.27)
				)
				(justify left bottom)
				(hide yes)
			)
		)
		(property "Dielectric" "X5R"
			(at 400.05 39.37 0)
			(effects
				(font
					(size 1.27 1.27)
				)
				(justify left bottom)
				(hide yes)
			)
		)
		(pin "2"
		)
		(pin "1"
		)
		(instances
			(project "usb-c-power-adapter"
				(path ""
					(reference "C40")
					(unit 1)
				)
			)
		)
	)
	(symbol
		(lib_id "antmicropower:GND")
		(at 240.03 81.28 0)
		(unit 1)
		(exclude_from_sim no)
		(in_bom yes)
		(on_board yes)
		(dnp no)
		(fields_autoplaced yes)
		(property "Reference" "#PWR033"
			(at 240.03 81.28 0)
			(effects
				(font
					(size 1.27 1.27)
				)
				(justify left)
				(hide yes)
			)
		)
		(property "Value" "GND"
			(at 240.03 85.725 0)
			(effects
				(font
					(size 1.27 1.27)
				)
			)
		)
		(property "Footprint" ""
			(at 240.03 81.28 0)
			(effects
				(font
					(size 1.27 1.27)
					(thickness 0.15)
				)
				(justify left bottom)
				(hide yes)
			)
		)
		(property "Datasheet" ""
			(at 240.03 81.28 0)
			(effects
				(font
					(size 1.27 1.27)
					(thickness 0.15)
				)
				(justify left bottom)
				(hide yes)
			)
		)
		(property "Description" ""
			(at 240.03 81.28 0)
			(effects
				(font
					(size 1.27 1.27)
				)
				(hide yes)
			)
		)
		(property "Author" "Antmicro"
			(at 248.92 88.9 0)
			(effects
				(font
					(size 1.27 1.27)
					(thickness 0.15)
				)
				(justify left bottom)
				(hide yes)
			)
		)
		(property "License" "Apache-2.0"
			(at 248.92 91.44 0)
			(effects
				(font
					(size 1.27 1.27)
					(thickness 0.15)
				)
				(justify left bottom)
				(hide yes)
			)
		)
		(pin "1"
		)
		(instances
			(project "usb-c-power-adapter"
				(path ""
					(reference "#PWR033")
					(unit 1)
				)
			)
		)
	)
	(symbol
		(lib_id "antmicroFerriteBeadsandChips:FB_10Z_10A_WE-MPSB_1206")
		(at 39.37 73.66 0)
		(unit 1)
		(exclude_from_sim no)
		(in_bom yes)
		(on_board yes)
		(dnp no)
		(property "Reference" "FB1"
			(at 41.656 77.216 0)
			(effects
				(font
					(size 1.27 1.27)
					(thickness 0.15)
				)
			)
		)
		(property "Value" "FB_10Z_10A_WE-MPSB_1206"
			(at 53.34 76.2 0)
			(effects
				(font
					(size 1.27 1.27)
					(thickness 0.15)
				)
				(justify left bottom)
				(hide yes)
			)
		)
		(property "Footprint" "antmicro-footprints:FB_1206_3216Metric"
			(at 53.34 81.28 0)
			(effects
				(font
					(size 1.27 1.27)
					(thickness 0.15)
				)
				(justify left bottom)
				(hide yes)
			)
		)
		(property "Datasheet" "https://www.we-online.com/catalog/datasheet/74279221100.pdf"
			(at 53.34 83.82 0)
			(effects
				(font
					(size 1.27 1.27)
					(thickness 0.15)
				)
				(justify left bottom)
				(hide yes)
			)
		)
		(property "Description" "Ferrite Bead, 1206 [3216 Metric], 10 ohm, 10.5 A, WE-MPSB, 0.003 ohm, ± 25%, High Current"
			(at 39.37 73.66 0)
			(effects
				(font
					(size 1.27 1.27)
				)
				(hide yes)
			)
		)
		(property "MPN" "74279221100"
			(at 53.34 86.36 0)
			(effects
				(font
					(size 1.27 1.27)
					(thickness 0.15)
				)
				(justify left bottom)
				(hide yes)
			)
		)
		(property "Manufacturer" "Würth Elektronik"
			(at 53.34 88.9 0)
			(effects
				(font
					(size 1.27 1.27)
					(thickness 0.15)
				)
				(justify left bottom)
				(hide yes)
			)
		)
		(property "Author" "Antmicro"
			(at 53.34 91.44 0)
			(effects
				(font
					(size 1.27 1.27)
					(thickness 0.15)
				)
				(justify left bottom)
				(hide yes)
			)
		)
		(property "License" "Apache-2.0"
			(at 53.34 93.98 0)
			(effects
				(font
					(size 1.27 1.27)
					(thickness 0.15)
				)
				(justify left bottom)
				(hide yes)
			)
		)
		(property "Val" "10Z/10A"
			(at 41.656 79.756 0)
			(effects
				(font
					(size 1.27 1.27)
				)
			)
		)
		(property "Current" ""
			(at 59.69 96.52 0)
			(effects
				(font
					(size 1.27 1.27)
					(thickness 0.15)
				)
				(justify left bottom)
				(hide yes)
			)
		)
		(pin "1"
		)
		(pin "2"
		)
		(instances
			(project "usb-c-power-adapter"
				(path ""
					(reference "FB1")
					(unit 1)
				)
			)
		)
	)
	(symbol
		(lib_id "antmicroCapacitors0402:C_1n2_50V_0402")
		(at 185.42 81.28 0)
		(unit 1)
		(exclude_from_sim no)
		(in_bom no)
		(on_board yes)
		(dnp yes)
		(fields_autoplaced yes)
		(property "Reference" "C14"
			(at 187.9663 74.93 0)
			(effects
				(font
					(size 1.27 1.27)
				)
			)
		)
		(property "Value" "C_1n2_50V_0402"
			(at 185.42 85.09 0)
			(effects
				(font
					(size 1.27 1.27)
				)
				(justify left)
				(hide yes)
			)
		)
		(property "Footprint" "antmicro-footprints:C_0402_1005Metric"
			(at 190.5 76.2 0)
			(effects
				(font
					(size 1.27 1.27)
					(thickness 0.15)
				)
				(justify left bottom)
				(hide yes)
			)
		)
		(property "Datasheet" "https://www.murata.com/products/productdetail?partno=GCM155R71H122KA37%23"
			(at 185.42 81.28 0)
			(effects
				(font
					(size 1.27 1.27)
					(thickness 0.15)
				)
				(justify left bottom)
				(hide yes)
			)
		)
		(property "Description" "SMD Multilayer Ceramic Capacitor, 1200 pF, 50 V, 0402 [1005 Metric], ± 10%, X7R, GCM"
			(at 185.42 81.28 0)
			(effects
				(font
					(size 1.27 1.27)
				)
				(hide yes)
			)
		)
		(property "Manufacturer" "Murata"
			(at 190.5 71.12 0)
			(effects
				(font
					(size 1.27 1.27)
					(thickness 0.15)
				)
				(justify left bottom)
				(hide yes)
			)
		)
		(property "MPN" "GCM155R71H122KA37D"
			(at 190.5 73.66 0)
			(effects
				(font
					(size 1.27 1.27)
					(thickness 0.15)
				)
				(justify left bottom)
				(hide yes)
			)
		)
		(property "Val" "1n2"
			(at 187.9663 77.47 0)
			(effects
				(font
					(size 1.27 1.27)
					(thickness 0.15)
				)
			)
		)
		(property "License" "Apache-2.0"
			(at 205.74 104.14 0)
			(effects
				(font
					(size 1.27 1.27)
					(thickness 0.15)
				)
				(justify left bottom)
				(hide yes)
			)
		)
		(property "Author" "Antmicro"
			(at 205.74 106.68 0)
			(effects
				(font
					(size 1.27 1.27)
					(thickness 0.15)
				)
				(justify left bottom)
				(hide yes)
			)
		)
		(property "Voltage" "50V"
			(at 205.74 109.22 0)
			(effects
				(font
					(size 1.27 1.27)
				)
				(justify left bottom)
				(hide yes)
			)
		)
		(property "Dielectric" ""
			(at 205.74 111.76 0)
			(effects
				(font
					(size 1.27 1.27)
				)
				(justify left bottom)
				(hide yes)
			)
		)
		(pin "1"
		)
		(pin "2"
		)
		(instances
			(project "usb-c-power-adapter"
				(path ""
					(reference "C14")
					(unit 1)
				)
			)
		)
	)
	(symbol
		(lib_id "antmicroResistors0402:R_0R_0402")
		(at 95.25 104.14 0)
		(unit 1)
		(exclude_from_sim no)
		(in_bom yes)
		(on_board yes)
		(dnp no)
		(property "Reference" "R6"
			(at 98.044 102.108 0)
			(effects
				(font
					(size 1.27 1.27)
				)
			)
		)
		(property "Value" "R_0R_0402"
			(at 95.25 107.95 0)
			(effects
				(font
					(size 1.27 1.27)
				)
				(justify left)
				(hide yes)
			)
		)
		(property "Footprint" "antmicro-footprints:R_0402_1005Metric"
			(at 100.33 99.06 0)
			(effects
				(font
					(size 1.27 1.27)
					(thickness 0.15)
				)
				(justify left bottom)
				(hide yes)
			)
		)
		(property "Datasheet" "https://industrial.panasonic.com/cdbs/www-data/pdf/RDA0000/AOA0000C301.pdf"
			(at 95.25 104.14 0)
			(effects
				(font
					(size 1.27 1.27)
					(thickness 0.15)
				)
				(justify left bottom)
				(hide yes)
			)
		)
		(property "Description" "SMD Chip Resistor, Jumper, 0 ohm, 100 mW, 0402 [1005 Metric], Thick Film, General Purpose"
			(at 95.25 104.14 0)
			(effects
				(font
					(size 1.27 1.27)
				)
				(hide yes)
			)
		)
		(property "Manufacturer" "Panasonic"
			(at 100.33 93.98 0)
			(effects
				(font
					(size 1.27 1.27)
					(thickness 0.15)
				)
				(justify left bottom)
				(hide yes)
			)
		)
		(property "MPN" "ERJ2GE0R00X"
			(at 100.33 96.52 0)
			(effects
				(font
					(size 1.27 1.27)
					(thickness 0.15)
				)
				(justify left bottom)
				(hide yes)
			)
		)
		(property "Val" "0R"
			(at 97.79 104.14 0)
			(effects
				(font
					(size 1.27 1.27)
					(thickness 0.15)
				)
			)
		)
		(property "License" "Apache-2.0"
			(at 115.57 129.54 0)
			(effects
				(font
					(size 1.27 1.27)
					(thickness 0.15)
				)
				(justify left bottom)
				(hide yes)
			)
		)
		(property "Author" "Antmicro"
			(at 115.57 132.08 0)
			(effects
				(font
					(size 1.27 1.27)
					(thickness 0.15)
				)
				(justify left bottom)
				(hide yes)
			)
		)
		(property "Tolerance" "~"
			(at 115.57 114.3 0)
			(effects
				(font
					(size 1.27 1.27)
				)
				(justify left bottom)
				(hide yes)
			)
		)
		(property "Current" "1A"
			(at 96.52 104.775 0)
			(effects
				(font
					(size 1.27 1.27)
					(thickness 0.15)
				)
				(justify left bottom)
				(hide yes)
			)
		)
		(pin "1"
		)
		(pin "2"
		)
		(instances
			(project "usb-c-power-adapter"
				(path ""
					(reference "R6")
					(unit 1)
				)
			)
		)
	)
	(symbol
		(lib_id "antmicropower:+5V")
		(at 374.65 93.98 0)
		(unit 1)
		(exclude_from_sim no)
		(in_bom yes)
		(on_board yes)
		(dnp no)
		(fields_autoplaced yes)
		(property "Reference" "#PWR072"
			(at 389.89 96.52 0)
			(effects
				(font
					(size 1.27 1.27)
					(thickness 0.15)
				)
				(justify left bottom)
				(hide yes)
			)
		)
		(property "Value" "+5V"
			(at 374.65 88.9 0)
			(effects
				(font
					(size 1.27 1.27)
					(thickness 0.15)
				)
			)
		)
		(property "Footprint" ""
			(at 389.89 101.6 0)
			(effects
				(font
					(size 1.27 1.27)
					(thickness 0.15)
				)
				(justify left bottom)
				(hide yes)
			)
		)
		(property "Datasheet" ""
			(at 389.89 104.14 0)
			(effects
				(font
					(size 1.27 1.27)
					(thickness 0.15)
				)
				(justify left bottom)
				(hide yes)
			)
		)
		(property "Description" ""
			(at 374.65 93.98 0)
			(effects
				(font
					(size 1.27 1.27)
				)
				(hide yes)
			)
		)
		(property "Author" "Antmicro"
			(at 389.89 101.6 0)
			(effects
				(font
					(size 1.27 1.27)
					(thickness 0.15)
				)
				(justify left bottom)
				(hide yes)
			)
		)
		(property "License" "Apache-2.0"
			(at 389.89 104.14 0)
			(effects
				(font
					(size 1.27 1.27)
					(thickness 0.15)
				)
				(justify left bottom)
				(hide yes)
			)
		)
		(pin "1"
		)
		(instances
			(project "usb-c-power-adapter"
				(path ""
					(reference "#PWR072")
					(unit 1)
				)
			)
		)
	)
	(symbol
		(lib_id "antmicropower:+12V")
		(at 163.83 82.55 0)
		(unit 1)
		(exclude_from_sim no)
		(in_bom yes)
		(on_board yes)
		(dnp no)
		(fields_autoplaced yes)
		(property "Reference" "#PWR068"
			(at 163.83 86.36 0)
			(effects
				(font
					(size 1.27 1.27)
				)
				(hide yes)
			)
		)
		(property "Value" "+12V"
			(at 163.83 77.47 0)
			(effects
				(font
					(size 1.27 1.27)
				)
			)
		)
		(property "Footprint" ""
			(at 163.83 82.55 0)
			(effects
				(font
					(size 1.27 1.27)
				)
				(hide yes)
			)
		)
		(property "Datasheet" ""
			(at 163.83 82.55 0)
			(effects
				(font
					(size 1.27 1.27)
				)
				(hide yes)
			)
		)
		(property "Description" ""
			(at 163.83 82.55 0)
			(effects
				(font
					(size 1.27 1.27)
				)
				(hide yes)
			)
		)
		(pin "1"
		)
		(instances
			(project "usb-c-power-adapter"
				(path ""
					(reference "#PWR068")
					(unit 1)
				)
			)
		)
	)
	(symbol
		(lib_id "antmicroCapacitorsmisc:C_47u_25V_1206")
		(at 269.24 91.44 90)
		(unit 1)
		(exclude_from_sim no)
		(in_bom yes)
		(on_board yes)
		(dnp no)
		(fields_autoplaced yes)
		(property "Reference" "C20"
			(at 271.78 86.3536 90)
			(effects
				(font
					(size 1.27 1.27)
					(thickness 0.15)
				)
				(justify right)
			)
		)
		(property "Value" "C_47u_25V_1206"
			(at 281.94 76.2 0)
			(effects
				(font
					(size 1.27 1.27)
					(thickness 0.15)
				)
				(justify left bottom)
				(hide yes)
			)
		)
		(property "Footprint" "antmicro-footprints:C_1206_3216Metric"
			(at 284.48 76.2 0)
			(effects
				(font
					(size 1.27 1.27)
					(thickness 0.15)
				)
				(justify left bottom)
				(hide yes)
			)
		)
		(property "Datasheet" "https://product.tdk.com/en/search/capacitor/ceramic/mlcc/info?part_no=C3216X5R1E476M160AC"
			(at 287.02 76.2 0)
			(effects
				(font
					(size 1.27 1.27)
					(thickness 0.15)
				)
				(justify left bottom)
				(hide yes)
			)
		)
		(property "Description" "SMD Multilayer Ceramic Capacitor, 47 µF, 25 V, 1206 [3216 Metric], ± 20%, X5R"
			(at 269.24 91.44 0)
			(effects
				(font
					(size 1.27 1.27)
				)
				(hide yes)
			)
		)
		(property "MPN" "C3216X5R1E476M160AC"
			(at 289.56 76.2 0)
			(effects
				(font
					(size 1.27 1.27)
					(thickness 0.15)
				)
				(justify left bottom)
				(hide yes)
			)
		)
		(property "Val" "47u"
			(at 271.78 88.8936 90)
			(effects
				(font
					(size 1.27 1.27)
					(thickness 0.15)
				)
				(justify right)
			)
		)
		(property "Voltage" "25V"
			(at 271.78 91.4336 90)
			(effects
				(font
					(size 1.27 1.27)
					(thickness 0.15)
				)
				(justify right)
			)
		)
		(property "Author" "Antmicro"
			(at 292.1 76.2 0)
			(effects
				(font
					(size 1.27 1.27)
					(thickness 0.15)
				)
				(justify left bottom)
				(hide yes)
			)
		)
		(property "License" "Apache-2.0"
			(at 294.64 76.2 0)
			(effects
				(font
					(size 1.27 1.27)
					(thickness 0.15)
				)
				(justify left bottom)
				(hide yes)
			)
		)
		(property "Manufacturer" "TDK"
			(at 297.18 76.2 0)
			(effects
				(font
					(size 1.27 1.27)
					(thickness 0.15)
				)
				(justify left bottom)
				(hide yes)
			)
		)
		(property "Dielectric" "X5R"
			(at 299.72 76.2 0)
			(effects
				(font
					(size 1.27 1.27)
					(thickness 0.15)
				)
				(justify left bottom)
				(hide yes)
			)
		)
		(property "Public" "False"
			(at 302.26 71.12 0)
			(effects
				(font
					(size 1.27 1.27)
				)
				(justify left bottom)
				(hide yes)
			)
		)
		(pin "2"
		)
		(pin "1"
		)
		(instances
			(project "usb-c-power-adapter"
				(path ""
					(reference "C20")
					(unit 1)
				)
			)
		)
	)
	(symbol
		(lib_id "antmicroCapacitors0402:C_33n_0402")
		(at 72.39 107.95 270)
		(unit 1)
		(exclude_from_sim no)
		(in_bom yes)
		(on_board yes)
		(dnp no)
		(fields_autoplaced yes)
		(property "Reference" "C5"
			(at 74.93 109.2262 90)
			(effects
				(font
					(size 1.27 1.27)
				)
				(justify left)
			)
		)
		(property "Value" "C_33n_0402"
			(at 68.58 107.95 0)
			(effects
				(font
					(size 1.27 1.27)
				)
				(justify left)
				(hide yes)
			)
		)
		(property "Footprint" "antmicro-footprints:C_0402_1005Metric"
			(at 77.47 113.03 0)
			(effects
				(font
					(size 1.27 1.27)
					(thickness 0.15)
				)
				(justify left bottom)
				(hide yes)
			)
		)
		(property "Datasheet" "https://www.murata.com/products/productdetail?partno=GCM155R71E333KA55%23"
			(at 72.39 107.95 0)
			(effects
				(font
					(size 1.27 1.27)
					(thickness 0.15)
				)
				(justify left bottom)
				(hide yes)
			)
		)
		(property "Description" "SMD Multilayer Ceramic Capacitor, 33000 pF, 25 V, 0402 [1005 Metric], ± 10%, X7R, MC"
			(at 72.39 107.95 0)
			(effects
				(font
					(size 1.27 1.27)
				)
				(hide yes)
			)
		)
		(property "Manufacturer" "Murata"
			(at 82.55 113.03 0)
			(effects
				(font
					(size 1.27 1.27)
					(thickness 0.15)
				)
				(justify left bottom)
				(hide yes)
			)
		)
		(property "MPN" "GCM155R71E333KA55D"
			(at 80.01 113.03 0)
			(effects
				(font
					(size 1.27 1.27)
					(thickness 0.15)
				)
				(justify left bottom)
				(hide yes)
			)
		)
		(property "Val" "33n"
			(at 74.93 111.7663 90)
			(effects
				(font
					(size 1.27 1.27)
					(thickness 0.15)
				)
				(justify left)
			)
		)
		(property "License" "Apache-2.0"
			(at 49.53 128.27 0)
			(effects
				(font
					(size 1.27 1.27)
					(thickness 0.15)
				)
				(justify left bottom)
				(hide yes)
			)
		)
		(property "Author" "Antmicro"
			(at 46.99 128.27 0)
			(effects
				(font
					(size 1.27 1.27)
					(thickness 0.15)
				)
				(justify left bottom)
				(hide yes)
			)
		)
		(property "Voltage" ""
			(at 44.45 128.27 0)
			(effects
				(font
					(size 1.27 1.27)
				)
				(justify left bottom)
				(hide yes)
			)
		)
		(property "Dielectric" ""
			(at 41.91 128.27 0)
			(effects
				(font
					(size 1.27 1.27)
				)
				(justify left bottom)
				(hide yes)
			)
		)
		(pin "1"
		)
		(pin "2"
		)
		(instances
			(project "usb-c-power-adapter"
				(path ""
					(reference "C5")
					(unit 1)
				)
			)
		)
	)
	(symbol
		(lib_id "antmicropower:GND")
		(at 295.91 93.98 0)
		(mirror y)
		(unit 1)
		(exclude_from_sim no)
		(in_bom yes)
		(on_board yes)
		(dnp no)
		(fields_autoplaced yes)
		(property "Reference" "#PWR023"
			(at 295.91 93.98 0)
			(effects
				(font
					(size 1.27 1.27)
				)
				(justify left)
				(hide yes)
			)
		)
		(property "Value" "GND"
			(at 295.91 98.425 0)
			(effects
				(font
					(size 1.27 1.27)
				)
			)
		)
		(property "Footprint" ""
			(at 295.91 93.98 0)
			(effects
				(font
					(size 1.27 1.27)
					(thickness 0.15)
				)
				(justify left bottom)
				(hide yes)
			)
		)
		(property "Datasheet" ""
			(at 295.91 93.98 0)
			(effects
				(font
					(size 1.27 1.27)
					(thickness 0.15)
				)
				(justify left bottom)
				(hide yes)
			)
		)
		(property "Description" ""
			(at 295.91 93.98 0)
			(effects
				(font
					(size 1.27 1.27)
				)
				(hide yes)
			)
		)
		(property "Author" "Antmicro"
			(at 287.02 101.6 0)
			(effects
				(font
					(size 1.27 1.27)
					(thickness 0.15)
				)
				(justify left bottom)
				(hide yes)
			)
		)
		(property "License" "Apache-2.0"
			(at 287.02 104.14 0)
			(effects
				(font
					(size 1.27 1.27)
					(thickness 0.15)
				)
				(justify left bottom)
				(hide yes)
			)
		)
		(pin "1"
		)
		(instances
			(project "usb-c-power-adapter"
				(path ""
					(reference "#PWR023")
					(unit 1)
				)
			)
		)
	)
	(symbol
		(lib_id "antmicropower:GND")
		(at 106.68 116.84 0)
		(unit 1)
		(exclude_from_sim no)
		(in_bom yes)
		(on_board yes)
		(dnp no)
		(fields_autoplaced yes)
		(property "Reference" "#PWR014"
			(at 106.68 116.84 0)
			(effects
				(font
					(size 1.27 1.27)
				)
				(justify left)
				(hide yes)
			)
		)
		(property "Value" "GND"
			(at 106.68 121.285 0)
			(effects
				(font
					(size 1.27 1.27)
				)
			)
		)
		(property "Footprint" ""
			(at 106.68 116.84 0)
			(effects
				(font
					(size 1.27 1.27)
					(thickness 0.15)
				)
				(justify left bottom)
				(hide yes)
			)
		)
		(property "Datasheet" ""
			(at 106.68 116.84 0)
			(effects
				(font
					(size 1.27 1.27)
					(thickness 0.15)
				)
				(justify left bottom)
				(hide yes)
			)
		)
		(property "Description" ""
			(at 106.68 116.84 0)
			(effects
				(font
					(size 1.27 1.27)
				)
				(hide yes)
			)
		)
		(property "Author" "Antmicro"
			(at 115.57 124.46 0)
			(effects
				(font
					(size 1.27 1.27)
					(thickness 0.15)
				)
				(justify left bottom)
				(hide yes)
			)
		)
		(property "License" "Apache-2.0"
			(at 115.57 127 0)
			(effects
				(font
					(size 1.27 1.27)
					(thickness 0.15)
				)
				(justify left bottom)
				(hide yes)
			)
		)
		(pin "1"
		)
		(instances
			(project "usb-c-power-adapter"
				(path ""
					(reference "#PWR014")
					(unit 1)
				)
			)
		)
	)
	(symbol
		(lib_id "antmicropower:+5V")
		(at 153.67 166.37 0)
		(unit 1)
		(exclude_from_sim no)
		(in_bom yes)
		(on_board yes)
		(dnp no)
		(fields_autoplaced yes)
		(property "Reference" "#PWR070"
			(at 168.91 168.91 0)
			(effects
				(font
					(size 1.27 1.27)
					(thickness 0.15)
				)
				(justify left bottom)
				(hide yes)
			)
		)
		(property "Value" "+5V"
			(at 153.67 161.29 0)
			(effects
				(font
					(size 1.27 1.27)
					(thickness 0.15)
				)
			)
		)
		(property "Footprint" ""
			(at 168.91 173.99 0)
			(effects
				(font
					(size 1.27 1.27)
					(thickness 0.15)
				)
				(justify left bottom)
				(hide yes)
			)
		)
		(property "Datasheet" ""
			(at 168.91 176.53 0)
			(effects
				(font
					(size 1.27 1.27)
					(thickness 0.15)
				)
				(justify left bottom)
				(hide yes)
			)
		)
		(property "Description" ""
			(at 153.67 166.37 0)
			(effects
				(font
					(size 1.27 1.27)
				)
				(hide yes)
			)
		)
		(property "Author" "Antmicro"
			(at 168.91 173.99 0)
			(effects
				(font
					(size 1.27 1.27)
					(thickness 0.15)
				)
				(justify left bottom)
				(hide yes)
			)
		)
		(property "License" "Apache-2.0"
			(at 168.91 176.53 0)
			(effects
				(font
					(size 1.27 1.27)
					(thickness 0.15)
				)
				(justify left bottom)
				(hide yes)
			)
		)
		(pin "1"
		)
		(instances
			(project "usb-c-power-adapter"
				(path ""
					(reference "#PWR070")
					(unit 1)
				)
			)
		)
	)
	(symbol
		(lib_id "antmicropower:GND")
		(at 64.77 116.84 0)
		(unit 1)
		(exclude_from_sim no)
		(in_bom yes)
		(on_board yes)
		(dnp no)
		(fields_autoplaced yes)
		(property "Reference" "#PWR07"
			(at 64.77 116.84 0)
			(effects
				(font
					(size 1.27 1.27)
				)
				(justify left)
				(hide yes)
			)
		)
		(property "Value" "GND"
			(at 64.77 121.285 0)
			(effects
				(font
					(size 1.27 1.27)
				)
			)
		)
		(property "Footprint" ""
			(at 64.77 116.84 0)
			(effects
				(font
					(size 1.27 1.27)
					(thickness 0.15)
				)
				(justify left bottom)
				(hide yes)
			)
		)
		(property "Datasheet" ""
			(at 64.77 116.84 0)
			(effects
				(font
					(size 1.27 1.27)
					(thickness 0.15)
				)
				(justify left bottom)
				(hide yes)
			)
		)
		(property "Description" ""
			(at 64.77 116.84 0)
			(effects
				(font
					(size 1.27 1.27)
				)
				(hide yes)
			)
		)
		(property "Author" "Antmicro"
			(at 73.66 124.46 0)
			(effects
				(font
					(size 1.27 1.27)
					(thickness 0.15)
				)
				(justify left bottom)
				(hide yes)
			)
		)
		(property "License" "Apache-2.0"
			(at 73.66 127 0)
			(effects
				(font
					(size 1.27 1.27)
					(thickness 0.15)
				)
				(justify left bottom)
				(hide yes)
			)
		)
		(pin "1"
		)
		(instances
			(project "usb-c-power-adapter"
				(path ""
					(reference "#PWR07")
					(unit 1)
				)
			)
		)
	)
	(symbol
		(lib_id "antmicropower:GND")
		(at 195.58 186.69 0)
		(unit 1)
		(exclude_from_sim no)
		(in_bom yes)
		(on_board yes)
		(dnp no)
		(fields_autoplaced yes)
		(property "Reference" "#PWR076"
			(at 204.47 189.23 0)
			(effects
				(font
					(size 1.27 1.27)
					(thickness 0.15)
				)
				(justify left bottom)
				(hide yes)
			)
		)
		(property "Value" "GND"
			(at 195.58 191.135 0)
			(effects
				(font
					(size 1.27 1.27)
					(thickness 0.15)
				)
			)
		)
		(property "Footprint" ""
			(at 204.47 194.31 0)
			(effects
				(font
					(size 1.27 1.27)
					(thickness 0.15)
				)
				(justify left bottom)
				(hide yes)
			)
		)
		(property "Datasheet" ""
			(at 204.47 199.39 0)
			(effects
				(font
					(size 1.27 1.27)
					(thickness 0.15)
				)
				(justify left bottom)
				(hide yes)
			)
		)
		(property "Description" ""
			(at 195.58 186.69 0)
			(effects
				(font
					(size 1.27 1.27)
				)
				(hide yes)
			)
		)
		(property "Author" "Antmicro"
			(at 204.47 194.31 0)
			(effects
				(font
					(size 1.27 1.27)
					(thickness 0.15)
				)
				(justify left bottom)
				(hide yes)
			)
		)
		(property "License" "Apache-2.0"
			(at 204.47 196.85 0)
			(effects
				(font
					(size 1.27 1.27)
					(thickness 0.15)
				)
				(justify left bottom)
				(hide yes)
			)
		)
		(pin "1"
		)
		(instances
			(project "usb-c-power-adapter"
				(path ""
					(reference "#PWR076")
					(unit 1)
				)
			)
		)
	)
	(symbol
		(lib_id "antmicroCapacitors0402:C_1u_25V_0402")
		(at 391.16 101.6 90)
		(unit 1)
		(exclude_from_sim no)
		(in_bom yes)
		(on_board yes)
		(dnp no)
		(fields_autoplaced yes)
		(property "Reference" "C42"
			(at 393.7 97.7836 90)
			(effects
				(font
					(size 1.27 1.27)
					(thickness 0.15)
				)
				(justify right)
			)
		)
		(property "Value" "C_1u_25V_0402"
			(at 401.32 81.28 0)
			(effects
				(font
					(size 1.27 1.27)
					(thickness 0.15)
				)
				(justify left bottom)
				(hide yes)
			)
		)
		(property "Footprint" "antmicro-footprints:C_0402_1005Metric"
			(at 403.86 81.28 0)
			(effects
				(font
					(size 1.27 1.27)
					(thickness 0.15)
				)
				(justify left bottom)
				(hide yes)
			)
		)
		(property "Datasheet" "https://www.murata.com/products/productdetail?partno=GRM155R61E105KE11%23"
			(at 406.4 81.28 0)
			(effects
				(font
					(size 1.27 1.27)
					(thickness 0.15)
				)
				(justify left bottom)
				(hide yes)
			)
		)
		(property "Description" "SMD Multilayer Ceramic Capacitor, 1 µF, 25 V, 0402 [1005 Metric], ± 10%, X5R, GRM Series"
			(at 391.16 101.6 0)
			(effects
				(font
					(size 1.27 1.27)
				)
				(hide yes)
			)
		)
		(property "MPN" "GRM155R61E105KE11J"
			(at 408.94 81.28 0)
			(effects
				(font
					(size 1.27 1.27)
					(thickness 0.15)
				)
				(justify left bottom)
				(hide yes)
			)
		)
		(property "Manufacturer" "Murata"
			(at 411.48 81.28 0)
			(effects
				(font
					(size 1.27 1.27)
					(thickness 0.15)
				)
				(justify left bottom)
				(hide yes)
			)
		)
		(property "License" "Apache-2.0"
			(at 414.02 81.28 0)
			(effects
				(font
					(size 1.27 1.27)
					(thickness 0.15)
				)
				(justify left bottom)
				(hide yes)
			)
		)
		(property "Author" "Antmicro"
			(at 416.56 81.28 0)
			(effects
				(font
					(size 1.27 1.27)
					(thickness 0.15)
				)
				(justify left bottom)
				(hide yes)
			)
		)
		(property "Val" "1u"
			(at 393.7 100.3236 90)
			(effects
				(font
					(size 1.27 1.27)
					(thickness 0.15)
				)
				(justify right)
			)
		)
		(property "Voltage" "25V"
			(at 419.1 81.28 0)
			(effects
				(font
					(size 1.27 1.27)
				)
				(justify left bottom)
				(hide yes)
			)
		)
		(property "Dielectric" "X5R"
			(at 421.64 81.28 0)
			(effects
				(font
					(size 1.27 1.27)
				)
				(justify left bottom)
				(hide yes)
			)
		)
		(pin "2"
		)
		(pin "1"
		)
		(instances
			(project "usb-c-power-adapter"
				(path ""
					(reference "C42")
					(unit 1)
				)
			)
		)
	)
	(symbol
		(lib_id "antmicroFixedInductors:L_3u3_2.5A_1008")
		(at 118.11 228.6 0)
		(unit 1)
		(exclude_from_sim no)
		(in_bom yes)
		(on_board yes)
		(dnp no)
		(fields_autoplaced yes)
		(property "Reference" "L3"
			(at 120.65 223.52 0)
			(effects
				(font
					(size 1.27 1.27)
					(thickness 0.15)
				)
			)
		)
		(property "Value" "L_3u3_2.5A_1008"
			(at 133.35 231.14 0)
			(effects
				(font
					(size 1.27 1.27)
					(thickness 0.15)
				)
				(justify left bottom)
				(hide yes)
			)
		)
		(property "Footprint" "antmicro-footprints:L_1008_2520Metric"
			(at 133.35 236.22 0)
			(effects
				(font
					(size 1.27 1.27)
					(thickness 0.15)
				)
				(justify left bottom)
				(hide yes)
			)
		)
		(property "Datasheet" "https://product.tdk.com/system/files/dam/doc/product/inductor/inductor/smd/catalog/inductor_automotive_power_tfm252012alma_en.pdf"
			(at 133.35 238.76 0)
			(effects
				(font
					(size 1.27 1.27)
					(thickness 0.15)
				)
				(justify left bottom)
				(hide yes)
			)
		)
		(property "Description" "3.3 µH Shielded Thin Film Inductor 2 A 140mOhm Max 1008 (2520 Metric)"
			(at 118.11 228.6 0)
			(effects
				(font
					(size 1.27 1.27)
				)
				(hide yes)
			)
		)
		(property "MPN" "TFM252012ALMA3R3MTAA"
			(at 133.35 241.3 0)
			(effects
				(font
					(size 1.27 1.27)
					(thickness 0.15)
				)
				(justify left bottom)
				(hide yes)
			)
		)
		(property "ISat" "2.1 A"
			(at 133.35 243.84 0)
			(effects
				(font
					(size 1.27 1.27)
					(thickness 0.15)
				)
				(justify left bottom)
				(hide yes)
			)
		)
		(property "IMax" "2.5 A"
			(at 133.35 246.38 0)
			(effects
				(font
					(size 1.27 1.27)
					(thickness 0.15)
				)
				(justify left bottom)
				(hide yes)
			)
		)
		(property "Manufacturer" "TDK"
			(at 133.35 248.92 0)
			(effects
				(font
					(size 1.27 1.27)
					(thickness 0.15)
				)
				(justify left bottom)
				(hide yes)
			)
		)
		(property "Val" "3u3/2.5A"
			(at 120.65 226.06 0)
			(effects
				(font
					(size 1.27 1.27)
					(thickness 0.15)
				)
			)
		)
		(property "Size" "2.5x2.0"
			(at 133.35 251.46 0)
			(effects
				(font
					(size 1.27 1.27)
				)
				(justify left bottom)
				(hide yes)
			)
		)
		(property "Author" "Antmicro"
			(at 133.35 254 0)
			(effects
				(font
					(size 1.27 1.27)
					(thickness 0.15)
				)
				(justify left bottom)
				(hide yes)
			)
		)
		(property "License" "Apache-2.0"
			(at 133.35 256.54 0)
			(effects
				(font
					(size 1.27 1.27)
					(thickness 0.15)
				)
				(justify left bottom)
				(hide yes)
			)
		)
		(pin "2"
		)
		(pin "1"
		)
		(instances
			(project "usb-c-power-adapter"
				(path ""
					(reference "L3")
					(unit 1)
				)
			)
		)
	)
	(symbol
		(lib_id "antmicropower:GND")
		(at 139.7 250.19 0)
		(unit 1)
		(exclude_from_sim no)
		(in_bom yes)
		(on_board yes)
		(dnp no)
		(fields_autoplaced yes)
		(property "Reference" "#PWR067"
			(at 139.7 250.19 0)
			(effects
				(font
					(size 1.27 1.27)
				)
				(justify left)
				(hide yes)
			)
		)
		(property "Value" "GND"
			(at 139.7 254.635 0)
			(effects
				(font
					(size 1.27 1.27)
				)
			)
		)
		(property "Footprint" ""
			(at 139.7 250.19 0)
			(effects
				(font
					(size 1.27 1.27)
					(thickness 0.15)
				)
				(justify left bottom)
				(hide yes)
			)
		)
		(property "Datasheet" ""
			(at 139.7 250.19 0)
			(effects
				(font
					(size 1.27 1.27)
					(thickness 0.15)
				)
				(justify left bottom)
				(hide yes)
			)
		)
		(property "Description" ""
			(at 139.7 250.19 0)
			(effects
				(font
					(size 1.27 1.27)
				)
				(hide yes)
			)
		)
		(property "Author" "Antmicro"
			(at 148.59 257.81 0)
			(effects
				(font
					(size 1.27 1.27)
					(thickness 0.15)
				)
				(justify left bottom)
				(hide yes)
			)
		)
		(property "License" "Apache-2.0"
			(at 148.59 260.35 0)
			(effects
				(font
					(size 1.27 1.27)
					(thickness 0.15)
				)
				(justify left bottom)
				(hide yes)
			)
		)
		(pin "1"
		)
		(instances
			(project "usb-c-power-adapter"
				(path ""
					(reference "#PWR067")
					(unit 1)
				)
			)
		)
	)
	(symbol
		(lib_id "antmicroWire2BoardConnectors:Molex_Nano-Fit_1x2_1053131202")
		(at 378.46 50.8 0)
		(unit 1)
		(exclude_from_sim no)
		(in_bom yes)
		(on_board yes)
		(dnp no)
		(fields_autoplaced yes)
		(property "Reference" "J4"
			(at 384.81 50.8 0)
			(effects
				(font
					(size 1.27 1.27)
					(thickness 0.15)
				)
				(justify left)
			)
		)
		(property "Value" "Molex_Nano-Fit_1x2_1053131202"
			(at 391.795 55.88 0)
			(effects
				(font
					(size 1.27 1.27)
					(thickness 0.15)
				)
				(justify left bottom)
				(hide yes)
			)
		)
		(property "Footprint" "antmicro-footprints:Conn_Molex_Nano-Fit_1x2_1053131102"
			(at 391.795 58.42 0)
			(effects
				(font
					(size 1.27 1.27)
					(thickness 0.15)
				)
				(justify left bottom)
				(hide yes)
			)
		)
		(property "Datasheet" "https://tools.molex.com/pdm_docs/ps/PS-105300-100-001.pdf"
			(at 391.795 60.96 0)
			(effects
				(font
					(size 1.27 1.27)
					(thickness 0.15)
				)
				(justify left bottom)
				(hide yes)
			)
		)
		(property "Description" "Rectangular connector, header, Through Hole, Right Angle 2 position"
			(at 378.46 50.8 0)
			(effects
				(font
					(size 1.27 1.27)
				)
				(hide yes)
			)
		)
		(property "Manufacturer" "Molex"
			(at 391.795 63.5 0)
			(effects
				(font
					(size 1.27 1.27)
					(thickness 0.15)
				)
				(justify left bottom)
				(hide yes)
			)
		)
		(property "MPN" "1053131202"
			(at 384.81 53.34 0)
			(effects
				(font
					(size 1.27 1.27)
					(thickness 0.15)
				)
				(justify left)
			)
		)
		(property "Author" "Antmicro"
			(at 391.795 68.58 0)
			(effects
				(font
					(size 1.27 1.27)
					(thickness 0.15)
				)
				(justify left bottom)
				(hide yes)
			)
		)
		(property "License" "Apache-2.0"
			(at 391.795 71.12 0)
			(effects
				(font
					(size 1.27 1.27)
					(thickness 0.15)
				)
				(justify left bottom)
				(hide yes)
			)
		)
		(pin "1"
		)
		(pin "2"
		)
		(instances
			(project ""
				(path ""
					(reference "J4")
					(unit 1)
				)
			)
		)
	)
	(symbol
		(lib_id "antmicroCapacitors0402:C_100n_50V_X8L_0402")
		(at 111.76 175.26 180)
		(unit 1)
		(exclude_from_sim no)
		(in_bom yes)
		(on_board yes)
		(dnp no)
		(property "Reference" "C23"
			(at 108.966 172.466 0)
			(effects
				(font
					(size 1.27 1.27)
					(thickness 0.15)
				)
			)
		)
		(property "Value" "C_100n_50V_X8L_0402"
			(at 96.52 152.4 0)
			(effects
				(font
					(size 1.27 1.27)
					(thickness 0.15)
				)
				(justify left bottom)
				(hide yes)
			)
		)
		(property "Footprint" "antmicro-footprints:C_0402_1005Metric"
			(at 96.52 149.86 0)
			(effects
				(font
					(size 1.27 1.27)
					(thickness 0.15)
				)
				(justify left bottom)
				(hide yes)
			)
		)
		(property "Datasheet" "https://www.murata.com/products/productdetail?partno=GCM155L8EH104KE07%23"
			(at 96.52 147.32 0)
			(effects
				(font
					(size 1.27 1.27)
					(thickness 0.15)
				)
				(justify left bottom)
				(hide yes)
			)
		)
		(property "Description" "SMD Multilayer Ceramic Capacitor, 100nF, 50V, 0402, ±10%, X8L"
			(at 111.76 175.26 0)
			(effects
				(font
					(size 1.27 1.27)
				)
				(hide yes)
			)
		)
		(property "MPN" "GCM155L8EH104KE07D"
			(at 96.52 144.78 0)
			(effects
				(font
					(size 1.27 1.27)
					(thickness 0.15)
				)
				(justify left bottom)
				(hide yes)
			)
		)
		(property "Val" "100n"
			(at 109.474 178.054 0)
			(effects
				(font
					(size 1.27 1.27)
					(thickness 0.15)
				)
			)
		)
		(property "Voltage" "50V"
			(at 96.52 165.1 0)
			(effects
				(font
					(size 1.27 1.27)
					(thickness 0.15)
				)
				(justify left bottom)
				(hide yes)
			)
		)
		(property "Dielectric" "X8L"
			(at 96.52 162.56 0)
			(effects
				(font
					(size 1.27 1.27)
					(thickness 0.15)
				)
				(justify left bottom)
				(hide yes)
			)
		)
		(property "Manufacturer" "Murata"
			(at 96.52 160.02 0)
			(effects
				(font
					(size 1.27 1.27)
					(thickness 0.15)
				)
				(justify left bottom)
				(hide yes)
			)
		)
		(property "License" "Apache-2.0"
			(at 96.52 157.48 0)
			(effects
				(font
					(size 1.27 1.27)
					(thickness 0.15)
				)
				(justify left bottom)
				(hide yes)
			)
		)
		(property "Author" "Antmicro"
			(at 96.52 154.94 0)
			(effects
				(font
					(size 1.27 1.27)
					(thickness 0.15)
				)
				(justify left bottom)
				(hide yes)
			)
		)
		(pin "1"
		)
		(pin "2"
		)
		(instances
			(project "usb-c-power-adapter"
				(path ""
					(reference "C23")
					(unit 1)
				)
			)
		)
	)
	(symbol
		(lib_id "antmicropower:GND")
		(at 365.76 107.95 0)
		(unit 1)
		(exclude_from_sim no)
		(in_bom yes)
		(on_board yes)
		(dnp no)
		(fields_autoplaced yes)
		(property "Reference" "#PWR055"
			(at 365.76 107.95 0)
			(effects
				(font
					(size 1.27 1.27)
				)
				(justify left)
				(hide yes)
			)
		)
		(property "Value" "GND"
			(at 365.76 112.395 0)
			(effects
				(font
					(size 1.27 1.27)
				)
			)
		)
		(property "Footprint" ""
			(at 365.76 107.95 0)
			(effects
				(font
					(size 1.27 1.27)
					(thickness 0.15)
				)
				(justify left bottom)
				(hide yes)
			)
		)
		(property "Datasheet" ""
			(at 365.76 107.95 0)
			(effects
				(font
					(size 1.27 1.27)
					(thickness 0.15)
				)
				(justify left bottom)
				(hide yes)
			)
		)
		(property "Description" ""
			(at 365.76 107.95 0)
			(effects
				(font
					(size 1.27 1.27)
				)
				(hide yes)
			)
		)
		(property "Author" "Antmicro"
			(at 374.65 115.57 0)
			(effects
				(font
					(size 1.27 1.27)
					(thickness 0.15)
				)
				(justify left bottom)
				(hide yes)
			)
		)
		(property "License" "Apache-2.0"
			(at 374.65 118.11 0)
			(effects
				(font
					(size 1.27 1.27)
					(thickness 0.15)
				)
				(justify left bottom)
				(hide yes)
			)
		)
		(pin "1"
		)
		(instances
			(project "usb-c-power-adapter"
				(path ""
					(reference "#PWR055")
					(unit 1)
				)
			)
		)
	)
	(symbol
		(lib_id "antmicroFuses:F_7A_1206")
		(at 355.6 50.8 0)
		(unit 1)
		(exclude_from_sim no)
		(in_bom yes)
		(on_board yes)
		(dnp no)
		(fields_autoplaced yes)
		(property "Reference" "F1"
			(at 358.14 45.72 0)
			(effects
				(font
					(size 1.27 1.27)
					(thickness 0.15)
				)
			)
		)
		(property "Value" "F_7A_1206"
			(at 377.19 58.42 0)
			(effects
				(font
					(size 1.27 1.27)
					(thickness 0.15)
				)
				(justify left bottom)
				(hide yes)
			)
		)
		(property "Footprint" "antmicro-footprints:F_1206_3216Metric"
			(at 377.19 60.96 0)
			(effects
				(font
					(size 1.27 1.27)
					(thickness 0.15)
				)
				(justify left bottom)
				(hide yes)
			)
		)
		(property "Datasheet" "https://us.schurter.com/pdf/english/typ_UST_1206.pdf"
			(at 377.19 63.5 0)
			(effects
				(font
					(size 1.27 1.27)
					(thickness 0.15)
				)
				(justify left bottom)
				(hide yes)
			)
		)
		(property "Description" "7 A 32 V AC 63 V DC Fuse Board Mount (Cartridge Style Excluded) Surface Mount 1206 (3216 Metric)"
			(at 355.6 50.8 0)
			(effects
				(font
					(size 1.27 1.27)
				)
				(hide yes)
			)
		)
		(property "Manufacturer" "Schurter"
			(at 377.19 66.04 0)
			(effects
				(font
					(size 1.27 1.27)
					(thickness 0.15)
				)
				(justify left bottom)
				(hide yes)
			)
		)
		(property "MPN" "3413.0326.11"
			(at 358.14 48.26 0)
			(effects
				(font
					(size 1.27 1.27)
					(thickness 0.15)
				)
			)
		)
		(property "Author" "Antmicro"
			(at 377.19 71.12 0)
			(effects
				(font
					(size 1.27 1.27)
					(thickness 0.15)
				)
				(justify left bottom)
				(hide yes)
			)
		)
		(property "License" "Apache-2.0"
			(at 377.19 73.66 0)
			(effects
				(font
					(size 1.27 1.27)
					(thickness 0.15)
				)
				(justify left bottom)
				(hide yes)
			)
		)
		(pin "1"
		)
		(pin "2"
		)
		(instances
			(project "usb-c-power-adapter"
				(path ""
					(reference "F1")
					(unit 1)
				)
			)
		)
	)
	(symbol
		(lib_id "antmicropower:GND")
		(at 304.8 64.77 0)
		(mirror y)
		(unit 1)
		(exclude_from_sim no)
		(in_bom yes)
		(on_board yes)
		(dnp no)
		(property "Reference" "#PWR020"
			(at 304.8 64.77 0)
			(effects
				(font
					(size 1.27 1.27)
				)
				(justify left)
				(hide yes)
			)
		)
		(property "Value" "GND"
			(at 304.8 68.58 0)
			(effects
				(font
					(size 1.27 1.27)
				)
			)
		)
		(property "Footprint" ""
			(at 304.8 64.77 0)
			(effects
				(font
					(size 1.27 1.27)
					(thickness 0.15)
				)
				(justify left bottom)
				(hide yes)
			)
		)
		(property "Datasheet" ""
			(at 304.8 64.77 0)
			(effects
				(font
					(size 1.27 1.27)
					(thickness 0.15)
				)
				(justify left bottom)
				(hide yes)
			)
		)
		(property "Description" ""
			(at 304.8 64.77 0)
			(effects
				(font
					(size 1.27 1.27)
				)
				(hide yes)
			)
		)
		(property "Author" "Antmicro"
			(at 295.91 72.39 0)
			(effects
				(font
					(size 1.27 1.27)
					(thickness 0.15)
				)
				(justify left bottom)
				(hide yes)
			)
		)
		(property "License" "Apache-2.0"
			(at 295.91 74.93 0)
			(effects
				(font
					(size 1.27 1.27)
					(thickness 0.15)
				)
				(justify left bottom)
				(hide yes)
			)
		)
		(pin "1"
		)
		(instances
			(project "usb-c-power-adapter"
				(path ""
					(reference "#PWR020")
					(unit 1)
				)
			)
		)
	)
	(symbol
		(lib_id "antmicropower:PWR_FLAG")
		(at 166.37 90.17 0)
		(unit 1)
		(exclude_from_sim no)
		(in_bom yes)
		(on_board yes)
		(dnp no)
		(property "Reference" "#FLG05"
			(at 166.37 88.265 0)
			(effects
				(font
					(size 1.27 1.27)
				)
				(hide yes)
			)
		)
		(property "Value" "PWR_FLAG"
			(at 165.1 91.44 0)
			(effects
				(font
					(size 1.27 1.27)
				)
			)
		)
		(property "Footprint" ""
			(at 166.37 90.17 0)
			(effects
				(font
					(size 1.27 1.27)
				)
				(hide yes)
			)
		)
		(property "Datasheet" ""
			(at 166.37 90.17 0)
			(effects
				(font
					(size 1.27 1.27)
				)
				(hide yes)
			)
		)
		(property "Description" ""
			(at 166.37 90.17 0)
			(effects
				(font
					(size 1.27 1.27)
				)
				(hide yes)
			)
		)
		(pin "1"
		)
		(instances
			(project "usb-c-power-adapter"
				(path ""
					(reference "#FLG05")
					(unit 1)
				)
			)
		)
	)
	(symbol
		(lib_id "antmicroResistors0402:R_1k_0402")
		(at 128.27 187.96 90)
		(unit 1)
		(exclude_from_sim no)
		(in_bom yes)
		(on_board yes)
		(dnp no)
		(fields_autoplaced yes)
		(property "Reference" "R41"
			(at 130.81 184.15 90)
			(effects
				(font
					(size 1.27 1.27)
					(thickness 0.15)
				)
				(justify right)
			)
		)
		(property "Value" "R_1k_0402"
			(at 140.97 167.64 0)
			(effects
				(font
					(size 1.27 1.27)
					(thickness 0.15)
				)
				(justify left bottom)
				(hide yes)
			)
		)
		(property "Footprint" "antmicro-footprints:R_0402_1005Metric"
			(at 143.51 167.64 0)
			(effects
				(font
					(size 1.27 1.27)
					(thickness 0.15)
				)
				(justify left bottom)
				(hide yes)
			)
		)
		(property "Datasheet" "https://www.bourns.com/docs/product-datasheets/cr.pdf"
			(at 146.05 167.64 0)
			(effects
				(font
					(size 1.27 1.27)
					(thickness 0.15)
				)
				(justify left bottom)
				(hide yes)
			)
		)
		(property "Description" "SMD Chip Resistor, 1 kohm, ± 1%, 63 mW, 0402 [1005 Metric], Thick Film, General Purpose"
			(at 128.27 187.96 0)
			(effects
				(font
					(size 1.27 1.27)
				)
				(hide yes)
			)
		)
		(property "MPN" "CR0402-FX-1001GLF"
			(at 148.59 167.64 0)
			(effects
				(font
					(size 1.27 1.27)
					(thickness 0.15)
				)
				(justify left bottom)
				(hide yes)
			)
		)
		(property "Manufacturer" "Bourns"
			(at 151.13 167.64 0)
			(effects
				(font
					(size 1.27 1.27)
					(thickness 0.15)
				)
				(justify left bottom)
				(hide yes)
			)
		)
		(property "License" "Apache-2.0"
			(at 153.67 167.64 0)
			(effects
				(font
					(size 1.27 1.27)
					(thickness 0.15)
				)
				(justify left bottom)
				(hide yes)
			)
		)
		(property "Author" "Antmicro"
			(at 156.21 167.64 0)
			(effects
				(font
					(size 1.27 1.27)
					(thickness 0.15)
				)
				(justify left bottom)
				(hide yes)
			)
		)
		(property "Val" "1k"
			(at 130.81 186.69 90)
			(effects
				(font
					(size 1.27 1.27)
					(thickness 0.15)
				)
				(justify right)
			)
		)
		(property "Tolerance" "1%"
			(at 138.43 167.64 0)
			(effects
				(font
					(size 1.27 1.27)
				)
				(justify left bottom)
				(hide yes)
			)
		)
		(pin "1"
		)
		(pin "2"
		)
		(instances
			(project "usb-c-power-adapter"
				(path ""
					(reference "R41")
					(unit 1)
				)
			)
		)
	)
	(symbol
		(lib_id "antmicroResistors0402:R_100k_0402")
		(at 147.32 100.33 0)
		(unit 1)
		(exclude_from_sim no)
		(in_bom yes)
		(on_board yes)
		(dnp no)
		(property "Reference" "R13"
			(at 149.86 96.266 0)
			(effects
				(font
					(size 1.27 1.27)
				)
			)
		)
		(property "Value" "R_100k_0402"
			(at 147.32 104.14 0)
			(effects
				(font
					(size 1.27 1.27)
				)
				(justify left)
				(hide yes)
			)
		)
		(property "Footprint" "antmicro-footprints:R_0402_1005Metric"
			(at 152.4 95.25 0)
			(effects
				(font
					(size 1.27 1.27)
					(thickness 0.15)
				)
				(justify left bottom)
				(hide yes)
			)
		)
		(property "Datasheet" "https://www.bourns.com/docs/product-datasheets/cr.pdf"
			(at 147.32 100.33 0)
			(effects
				(font
					(size 1.27 1.27)
					(thickness 0.15)
				)
				(justify left bottom)
				(hide yes)
			)
		)
		(property "Description" "SMD Chip Resistor, 100 kohm, ± 1%, 62.5 mW, 0402 [1005 Metric], Thick Film, General Purpose"
			(at 147.32 100.33 0)
			(effects
				(font
					(size 1.27 1.27)
				)
				(hide yes)
			)
		)
		(property "Manufacturer" "Bourns"
			(at 152.4 90.17 0)
			(effects
				(font
					(size 1.27 1.27)
					(thickness 0.15)
				)
				(justify left bottom)
				(hide yes)
			)
		)
		(property "MPN" "CR0402-FX-1003GLF"
			(at 152.4 92.71 0)
			(effects
				(font
					(size 1.27 1.27)
					(thickness 0.15)
				)
				(justify left bottom)
				(hide yes)
			)
		)
		(property "Val" "100k"
			(at 149.86 98.298 0)
			(effects
				(font
					(size 1.27 1.27)
					(thickness 0.15)
				)
			)
		)
		(property "License" "Apache-2.0"
			(at 167.64 125.73 0)
			(effects
				(font
					(size 1.27 1.27)
					(thickness 0.15)
				)
				(justify left bottom)
				(hide yes)
			)
		)
		(property "Author" "Antmicro"
			(at 167.64 128.27 0)
			(effects
				(font
					(size 1.27 1.27)
					(thickness 0.15)
				)
				(justify left bottom)
				(hide yes)
			)
		)
		(property "Tolerance" "1%"
			(at 167.64 110.49 0)
			(effects
				(font
					(size 1.27 1.27)
				)
				(justify left bottom)
				(hide yes)
			)
		)
		(pin "1"
		)
		(pin "2"
		)
		(instances
			(project "usb-c-power-adapter"
				(path ""
					(reference "R13")
					(unit 1)
				)
			)
		)
	)
	(symbol
		(lib_id "antmicropower:GND")
		(at 80.01 250.19 0)
		(unit 1)
		(exclude_from_sim no)
		(in_bom yes)
		(on_board yes)
		(dnp no)
		(property "Reference" "#PWR042"
			(at 80.01 250.19 0)
			(effects
				(font
					(size 1.27 1.27)
				)
				(justify left)
				(hide yes)
			)
		)
		(property "Value" "GND"
			(at 80.01 254 0)
			(effects
				(font
					(size 1.27 1.27)
				)
			)
		)
		(property "Footprint" ""
			(at 80.01 250.19 0)
			(effects
				(font
					(size 1.27 1.27)
					(thickness 0.15)
				)
				(justify left bottom)
				(hide yes)
			)
		)
		(property "Datasheet" ""
			(at 80.01 250.19 0)
			(effects
				(font
					(size 1.27 1.27)
					(thickness 0.15)
				)
				(justify left bottom)
				(hide yes)
			)
		)
		(property "Description" ""
			(at 80.01 250.19 0)
			(effects
				(font
					(size 1.27 1.27)
				)
				(hide yes)
			)
		)
		(property "Author" "Antmicro"
			(at 88.9 257.81 0)
			(effects
				(font
					(size 1.27 1.27)
					(thickness 0.15)
				)
				(justify left bottom)
				(hide yes)
			)
		)
		(property "License" "Apache-2.0"
			(at 88.9 260.35 0)
			(effects
				(font
					(size 1.27 1.27)
					(thickness 0.15)
				)
				(justify left bottom)
				(hide yes)
			)
		)
		(pin "1"
		)
		(instances
			(project "usb-c-power-adapter"
				(path ""
					(reference "#PWR042")
					(unit 1)
				)
			)
		)
	)
	(symbol
		(lib_id "antmicropower:GND")
		(at 78.74 82.55 0)
		(unit 1)
		(exclude_from_sim no)
		(in_bom yes)
		(on_board yes)
		(dnp no)
		(property "Reference" "#PWR010"
			(at 78.74 82.55 0)
			(effects
				(font
					(size 1.27 1.27)
				)
				(justify left)
				(hide yes)
			)
		)
		(property "Value" "GND"
			(at 78.74 86.36 0)
			(effects
				(font
					(size 1.27 1.27)
				)
			)
		)
		(property "Footprint" ""
			(at 78.74 82.55 0)
			(effects
				(font
					(size 1.27 1.27)
					(thickness 0.15)
				)
				(justify left bottom)
				(hide yes)
			)
		)
		(property "Datasheet" ""
			(at 78.74 82.55 0)
			(effects
				(font
					(size 1.27 1.27)
					(thickness 0.15)
				)
				(justify left bottom)
				(hide yes)
			)
		)
		(property "Description" ""
			(at 78.74 82.55 0)
			(effects
				(font
					(size 1.27 1.27)
				)
				(hide yes)
			)
		)
		(property "Author" "Antmicro"
			(at 87.63 90.17 0)
			(effects
				(font
					(size 1.27 1.27)
					(thickness 0.15)
				)
				(justify left bottom)
				(hide yes)
			)
		)
		(property "License" "Apache-2.0"
			(at 87.63 92.71 0)
			(effects
				(font
					(size 1.27 1.27)
					(thickness 0.15)
				)
				(justify left bottom)
				(hide yes)
			)
		)
		(pin "1"
		)
		(instances
			(project "usb-c-power-adapter"
				(path ""
					(reference "#PWR010")
					(unit 1)
				)
			)
		)
	)
	(symbol
		(lib_id "antmicropower:GND")
		(at 189.23 116.84 0)
		(unit 1)
		(exclude_from_sim no)
		(in_bom yes)
		(on_board yes)
		(dnp no)
		(fields_autoplaced yes)
		(property "Reference" "#PWR027"
			(at 189.23 116.84 0)
			(effects
				(font
					(size 1.27 1.27)
				)
				(justify left)
				(hide yes)
			)
		)
		(property "Value" "GND"
			(at 189.23 121.285 0)
			(effects
				(font
					(size 1.27 1.27)
				)
			)
		)
		(property "Footprint" ""
			(at 189.23 116.84 0)
			(effects
				(font
					(size 1.27 1.27)
					(thickness 0.15)
				)
				(justify left bottom)
				(hide yes)
			)
		)
		(property "Datasheet" ""
			(at 189.23 116.84 0)
			(effects
				(font
					(size 1.27 1.27)
					(thickness 0.15)
				)
				(justify left bottom)
				(hide yes)
			)
		)
		(property "Description" ""
			(at 189.23 116.84 0)
			(effects
				(font
					(size 1.27 1.27)
				)
				(hide yes)
			)
		)
		(property "Author" "Antmicro"
			(at 198.12 124.46 0)
			(effects
				(font
					(size 1.27 1.27)
					(thickness 0.15)
				)
				(justify left bottom)
				(hide yes)
			)
		)
		(property "License" "Apache-2.0"
			(at 198.12 127 0)
			(effects
				(font
					(size 1.27 1.27)
					(thickness 0.15)
				)
				(justify left bottom)
				(hide yes)
			)
		)
		(pin "1"
		)
		(instances
			(project "usb-c-power-adapter"
				(path ""
					(reference "#PWR027")
					(unit 1)
				)
			)
		)
	)
	(symbol
		(lib_id "antmicroCapacitorsmisc:C_10u_0805_35V")
		(at 69.85 81.28 90)
		(unit 1)
		(exclude_from_sim no)
		(in_bom yes)
		(on_board yes)
		(dnp no)
		(fields_autoplaced yes)
		(property "Reference" "C3"
			(at 72.39 77.4636 90)
			(effects
				(font
					(size 1.27 1.27)
					(thickness 0.15)
				)
				(justify right)
			)
		)
		(property "Value" "C_10u_0805_35V"
			(at 80.01 60.96 0)
			(effects
				(font
					(size 1.27 1.27)
					(thickness 0.15)
				)
				(justify left bottom)
				(hide yes)
			)
		)
		(property "Footprint" "antmicro-footprints:C_0805_2012Metric"
			(at 82.55 60.96 0)
			(effects
				(font
					(size 1.27 1.27)
					(thickness 0.15)
				)
				(justify left bottom)
				(hide yes)
			)
		)
		(property "Datasheet" "https://www.murata.com/products/productdetail?partno=GRM21BR6YA106KE43%23"
			(at 85.09 60.96 0)
			(effects
				(font
					(size 1.27 1.27)
					(thickness 0.15)
				)
				(justify left bottom)
				(hide yes)
			)
		)
		(property "Description" "SMD Multilayer Ceramic Capacitor, 10 µF, 35 V, 0805 [2012 Metric], ± 10%, X5R, GRM Series"
			(at 69.85 81.28 0)
			(effects
				(font
					(size 1.27 1.27)
				)
				(hide yes)
			)
		)
		(property "MPN" "GRM21BR6YA106KE43L"
			(at 87.63 60.96 0)
			(effects
				(font
					(size 1.27 1.27)
					(thickness 0.15)
				)
				(justify left bottom)
				(hide yes)
			)
		)
		(property "Manufacturer" "Murata"
			(at 90.17 60.96 0)
			(effects
				(font
					(size 1.27 1.27)
					(thickness 0.15)
				)
				(justify left bottom)
				(hide yes)
			)
		)
		(property "License" "Apache-2.0"
			(at 92.71 60.96 0)
			(effects
				(font
					(size 1.27 1.27)
					(thickness 0.15)
				)
				(justify left bottom)
				(hide yes)
			)
		)
		(property "Author" "Antmicro"
			(at 95.25 60.96 0)
			(effects
				(font
					(size 1.27 1.27)
					(thickness 0.15)
				)
				(justify left bottom)
				(hide yes)
			)
		)
		(property "Val" "10u"
			(at 72.39 80.0036 90)
			(effects
				(font
					(size 1.27 1.27)
					(thickness 0.15)
				)
				(justify right)
			)
		)
		(property "Voltage" "35V"
			(at 97.79 60.96 0)
			(effects
				(font
					(size 1.27 1.27)
				)
				(justify left bottom)
				(hide yes)
			)
		)
		(property "Dielectric" ""
			(at 100.33 60.96 0)
			(effects
				(font
					(size 1.27 1.27)
				)
				(justify left bottom)
				(hide yes)
			)
		)
		(property "Public" "False"
			(at 102.87 60.96 0)
			(effects
				(font
					(size 1.27 1.27)
				)
				(justify left bottom)
				(hide yes)
			)
		)
		(pin "2"
		)
		(pin "1"
		)
		(instances
			(project "usb-c-power-adapter"
				(path ""
					(reference "C3")
					(unit 1)
				)
			)
		)
	)
	(symbol
		(lib_id "antmicroResistors0402:R_5k23_0402")
		(at 128.27 172.72 270)
		(unit 1)
		(exclude_from_sim no)
		(in_bom yes)
		(on_board yes)
		(dnp no)
		(fields_autoplaced yes)
		(property "Reference" "R2"
			(at 130.81 173.99 90)
			(effects
				(font
					(size 1.27 1.27)
					(thickness 0.15)
				)
				(justify left)
			)
		)
		(property "Value" "R_5k23_0402"
			(at 115.57 193.04 0)
			(effects
				(font
					(size 1.27 1.27)
					(thickness 0.15)
				)
				(justify left bottom)
				(hide yes)
			)
		)
		(property "Footprint" "antmicro-footprints:R_0402_1005Metric"
			(at 113.03 193.04 0)
			(effects
				(font
					(size 1.27 1.27)
					(thickness 0.15)
				)
				(justify left bottom)
				(hide yes)
			)
		)
		(property "Datasheet" "https://www.farnell.com/datasheets/3795017.pdf"
			(at 110.49 193.04 0)
			(effects
				(font
					(size 1.27 1.27)
					(thickness 0.15)
				)
				(justify left bottom)
				(hide yes)
			)
		)
		(property "Description" "SMD Chip Resistor, 5.23 kohm, ± 1%, 63 mW, 0402 [1005 Metric], Thick Film, General Purpose"
			(at 128.27 172.72 0)
			(effects
				(font
					(size 1.27 1.27)
				)
				(hide yes)
			)
		)
		(property "MPN" "RC0402FR-075K23L"
			(at 107.95 193.04 0)
			(effects
				(font
					(size 1.27 1.27)
					(thickness 0.15)
				)
				(justify left bottom)
				(hide yes)
			)
		)
		(property "Manufacturer" "YAGEO"
			(at 105.41 193.04 0)
			(effects
				(font
					(size 1.27 1.27)
					(thickness 0.15)
				)
				(justify left bottom)
				(hide yes)
			)
		)
		(property "License" "Apache-2.0"
			(at 102.87 193.04 0)
			(effects
				(font
					(size 1.27 1.27)
					(thickness 0.15)
				)
				(justify left bottom)
				(hide yes)
			)
		)
		(property "Author" "Antmicro"
			(at 100.33 193.04 0)
			(effects
				(font
					(size 1.27 1.27)
					(thickness 0.15)
				)
				(justify left bottom)
				(hide yes)
			)
		)
		(property "Val" "5k23"
			(at 130.81 176.53 90)
			(effects
				(font
					(size 1.27 1.27)
					(thickness 0.15)
				)
				(justify left)
			)
		)
		(property "Tolerance" "1%"
			(at 118.11 193.04 0)
			(effects
				(font
					(size 1.27 1.27)
				)
				(justify left bottom)
				(hide yes)
			)
		)
		(pin "1"
		)
		(pin "2"
		)
		(instances
			(project "usb-c-power-adapter"
				(path ""
					(reference "R2")
					(unit 1)
				)
			)
		)
	)
	(symbol
		(lib_id "antmicropower:PWR_FLAG")
		(at 226.06 71.12 0)
		(unit 1)
		(exclude_from_sim no)
		(in_bom yes)
		(on_board yes)
		(dnp no)
		(property "Reference" "#FLG02"
			(at 226.06 69.215 0)
			(effects
				(font
					(size 1.27 1.27)
				)
				(hide yes)
			)
		)
		(property "Value" "PWR_FLAG"
			(at 225.425 66.04 0)
			(effects
				(font
					(size 1.27 1.27)
				)
			)
		)
		(property "Footprint" ""
			(at 226.06 71.12 0)
			(effects
				(font
					(size 1.27 1.27)
				)
				(hide yes)
			)
		)
		(property "Datasheet" ""
			(at 226.06 71.12 0)
			(effects
				(font
					(size 1.27 1.27)
				)
				(hide yes)
			)
		)
		(property "Description" ""
			(at 226.06 71.12 0)
			(effects
				(font
					(size 1.27 1.27)
				)
				(hide yes)
			)
		)
		(pin "1"
		)
		(instances
			(project "usb-c-power-adapter"
				(path ""
					(reference "#FLG02")
					(unit 1)
				)
			)
		)
	)
	(symbol
		(lib_id "antmicroCapacitorsmisc:C_22u_25V_0805")
		(at 269.24 76.2 90)
		(unit 1)
		(exclude_from_sim no)
		(in_bom yes)
		(on_board yes)
		(dnp no)
		(fields_autoplaced yes)
		(property "Reference" "C18"
			(at 271.78 71.1136 90)
			(effects
				(font
					(size 1.27 1.27)
					(thickness 0.15)
				)
				(justify right)
			)
		)
		(property "Value" "C_22u_25V_0805"
			(at 279.4 55.88 0)
			(effects
				(font
					(size 1.27 1.27)
					(thickness 0.15)
				)
				(justify left bottom)
				(hide yes)
			)
		)
		(property "Footprint" "antmicro-footprints:C_0805_2012Metric"
			(at 281.94 55.88 0)
			(effects
				(font
					(size 1.27 1.27)
					(thickness 0.15)
				)
				(justify left bottom)
				(hide yes)
			)
		)
		(property "Datasheet" "https://product.samsungsem.com/mlcc/CL21A226MAYNNN.do"
			(at 284.48 55.88 0)
			(effects
				(font
					(size 1.27 1.27)
					(thickness 0.15)
				)
				(justify left bottom)
				(hide yes)
			)
		)
		(property "Description" "SMT Multilayer Ceramic Capacitor, 22uF, +/-20%, 25V, X5R, 0805 [2012 Metric]"
			(at 269.24 76.2 0)
			(effects
				(font
					(size 1.27 1.27)
				)
				(hide yes)
			)
		)
		(property "MPN" "CL21A226MAYNNNE"
			(at 287.02 55.88 0)
			(effects
				(font
					(size 1.27 1.27)
					(thickness 0.15)
				)
				(justify left bottom)
				(hide yes)
			)
		)
		(property "Manufacturer" "Samsung Electro-Mechanics"
			(at 289.56 55.88 0)
			(effects
				(font
					(size 1.27 1.27)
					(thickness 0.15)
				)
				(justify left bottom)
				(hide yes)
			)
		)
		(property "License" "Apache-2.0"
			(at 292.1 55.88 0)
			(effects
				(font
					(size 1.27 1.27)
					(thickness 0.15)
				)
				(justify left bottom)
				(hide yes)
			)
		)
		(property "Author" "Antmicro"
			(at 294.64 55.88 0)
			(effects
				(font
					(size 1.27 1.27)
					(thickness 0.15)
				)
				(justify left bottom)
				(hide yes)
			)
		)
		(property "Val" "22u"
			(at 271.78 73.6536 90)
			(effects
				(font
					(size 1.27 1.27)
					(thickness 0.15)
				)
				(justify right)
			)
		)
		(property "Voltage" "25V"
			(at 271.78 76.1935 90)
			(effects
				(font
					(size 1.27 1.27)
				)
				(justify right)
			)
		)
		(property "Dielectric" "X5R"
			(at 299.72 55.88 0)
			(effects
				(font
					(size 1.27 1.27)
				)
				(justify left bottom)
				(hide yes)
			)
		)
		(property "Public" "False"
			(at 302.26 55.88 0)
			(effects
				(font
					(size 1.27 1.27)
				)
				(justify left bottom)
				(hide yes)
			)
		)
		(pin "1"
		)
		(pin "2"
		)
		(instances
			(project "usb-c-power-adapter"
				(path ""
					(reference "C18")
					(unit 1)
				)
			)
		)
	)
	(symbol
		(lib_id "antmicropower:GND")
		(at 198.12 81.28 0)
		(unit 1)
		(exclude_from_sim no)
		(in_bom yes)
		(on_board yes)
		(dnp no)
		(property "Reference" "#PWR028"
			(at 198.12 81.28 0)
			(effects
				(font
					(size 1.27 1.27)
				)
				(justify left)
				(hide yes)
			)
		)
		(property "Value" "GND"
			(at 198.755 84.455 0)
			(effects
				(font
					(size 1.27 1.27)
				)
				(justify left)
			)
		)
		(property "Footprint" ""
			(at 198.12 81.28 0)
			(effects
				(font
					(size 1.27 1.27)
					(thickness 0.15)
				)
				(justify left bottom)
				(hide yes)
			)
		)
		(property "Datasheet" ""
			(at 198.12 81.28 0)
			(effects
				(font
					(size 1.27 1.27)
					(thickness 0.15)
				)
				(justify left bottom)
				(hide yes)
			)
		)
		(property "Description" ""
			(at 198.12 81.28 0)
			(effects
				(font
					(size 1.27 1.27)
				)
				(hide yes)
			)
		)
		(property "Author" "Antmicro"
			(at 207.01 88.9 0)
			(effects
				(font
					(size 1.27 1.27)
					(thickness 0.15)
				)
				(justify left bottom)
				(hide yes)
			)
		)
		(property "License" "Apache-2.0"
			(at 207.01 91.44 0)
			(effects
				(font
					(size 1.27 1.27)
					(thickness 0.15)
				)
				(justify left bottom)
				(hide yes)
			)
		)
		(pin "1"
		)
		(instances
			(project "usb-c-power-adapter"
				(path ""
					(reference "#PWR028")
					(unit 1)
				)
			)
		)
	)
	(symbol
		(lib_id "antmicroCapacitors0402:C_100n_50V_X8L_0402")
		(at 96.52 81.28 90)
		(unit 1)
		(exclude_from_sim no)
		(in_bom yes)
		(on_board yes)
		(dnp no)
		(fields_autoplaced yes)
		(property "Reference" "C6"
			(at 99.06 77.4636 90)
			(effects
				(font
					(size 1.27 1.27)
					(thickness 0.15)
				)
				(justify right)
			)
		)
		(property "Value" "C_100n_50V_X8L_0402"
			(at 119.38 66.04 0)
			(effects
				(font
					(size 1.27 1.27)
					(thickness 0.15)
				)
				(justify left bottom)
				(hide yes)
			)
		)
		(property "Footprint" "antmicro-footprints:C_0402_1005Metric"
			(at 121.92 66.04 0)
			(effects
				(font
					(size 1.27 1.27)
					(thickness 0.15)
				)
				(justify left bottom)
				(hide yes)
			)
		)
		(property "Datasheet" "https://www.murata.com/products/productdetail?partno=GCM155L8EH104KE07%23"
			(at 124.46 66.04 0)
			(effects
				(font
					(size 1.27 1.27)
					(thickness 0.15)
				)
				(justify left bottom)
				(hide yes)
			)
		)
		(property "Description" "SMD Multilayer Ceramic Capacitor, 100nF, 50V, 0402, ±10%, X8L"
			(at 96.52 81.28 0)
			(effects
				(font
					(size 1.27 1.27)
				)
				(hide yes)
			)
		)
		(property "MPN" "GCM155L8EH104KE07D"
			(at 127 66.04 0)
			(effects
				(font
					(size 1.27 1.27)
					(thickness 0.15)
				)
				(justify left bottom)
				(hide yes)
			)
		)
		(property "Val" "100n"
			(at 99.06 80.0036 90)
			(effects
				(font
					(size 1.27 1.27)
					(thickness 0.15)
				)
				(justify right)
			)
		)
		(property "Voltage" "50V"
			(at 106.68 66.04 0)
			(effects
				(font
					(size 1.27 1.27)
					(thickness 0.15)
				)
				(justify left bottom)
				(hide yes)
			)
		)
		(property "Dielectric" "X8L"
			(at 109.22 66.04 0)
			(effects
				(font
					(size 1.27 1.27)
					(thickness 0.15)
				)
				(justify left bottom)
				(hide yes)
			)
		)
		(property "Manufacturer" "Murata"
			(at 111.76 66.04 0)
			(effects
				(font
					(size 1.27 1.27)
					(thickness 0.15)
				)
				(justify left bottom)
				(hide yes)
			)
		)
		(property "License" "Apache-2.0"
			(at 114.3 66.04 0)
			(effects
				(font
					(size 1.27 1.27)
					(thickness 0.15)
				)
				(justify left bottom)
				(hide yes)
			)
		)
		(property "Author" "Antmicro"
			(at 116.84 66.04 0)
			(effects
				(font
					(size 1.27 1.27)
					(thickness 0.15)
				)
				(justify left bottom)
				(hide yes)
			)
		)
		(pin "1"
		)
		(pin "2"
		)
		(instances
			(project "usb-c-power-adapter"
				(path ""
					(reference "C6")
					(unit 1)
				)
			)
		)
	)
	(symbol
		(lib_id "antmicropower:GND")
		(at 71.12 250.19 0)
		(unit 1)
		(exclude_from_sim no)
		(in_bom yes)
		(on_board yes)
		(dnp no)
		(property "Reference" "#PWR040"
			(at 71.12 250.19 0)
			(effects
				(font
					(size 1.27 1.27)
				)
				(justify left)
				(hide yes)
			)
		)
		(property "Value" "GND"
			(at 71.12 254 0)
			(effects
				(font
					(size 1.27 1.27)
				)
			)
		)
		(property "Footprint" ""
			(at 71.12 250.19 0)
			(effects
				(font
					(size 1.27 1.27)
					(thickness 0.15)
				)
				(justify left bottom)
				(hide yes)
			)
		)
		(property "Datasheet" ""
			(at 71.12 250.19 0)
			(effects
				(font
					(size 1.27 1.27)
					(thickness 0.15)
				)
				(justify left bottom)
				(hide yes)
			)
		)
		(property "Description" ""
			(at 71.12 250.19 0)
			(effects
				(font
					(size 1.27 1.27)
				)
				(hide yes)
			)
		)
		(property "Author" "Antmicro"
			(at 80.01 257.81 0)
			(effects
				(font
					(size 1.27 1.27)
					(thickness 0.15)
				)
				(justify left bottom)
				(hide yes)
			)
		)
		(property "License" "Apache-2.0"
			(at 80.01 260.35 0)
			(effects
				(font
					(size 1.27 1.27)
					(thickness 0.15)
				)
				(justify left bottom)
				(hide yes)
			)
		)
		(pin "1"
		)
		(instances
			(project "usb-c-power-adapter"
				(path ""
					(reference "#PWR040")
					(unit 1)
				)
			)
		)
	)
	(symbol
		(lib_id "antmicroLEDIndicationDiscrete:LED_G_0603_LG_L29K-G2J1-24-Z")
		(at 213.36 184.15 90)
		(unit 1)
		(exclude_from_sim no)
		(in_bom yes)
		(on_board yes)
		(dnp no)
		(fields_autoplaced yes)
		(property "Reference" "D9"
			(at 215.9 180.34 90)
			(effects
				(font
					(size 1.27 1.27)
					(thickness 0.15)
				)
				(justify right)
			)
		)
		(property "Value" "LED_G_0603_LG_L29K-G2J1-24-Z"
			(at 220.98 163.83 0)
			(effects
				(font
					(size 1.27 1.27)
					(thickness 0.15)
				)
				(justify left bottom)
				(hide yes)
			)
		)
		(property "Footprint" "antmicro-footprints:LED_0603_1608Metric_G"
			(at 223.52 163.83 0)
			(effects
				(font
					(size 1.27 1.27)
					(thickness 0.15)
				)
				(justify left bottom)
				(hide yes)
			)
		)
		(property "Datasheet" "https://look.ams-osram.com/m/19ee86b3ae0ee95b/original/LG-L29K.pdf"
			(at 226.06 163.83 0)
			(effects
				(font
					(size 1.27 1.27)
					(thickness 0.15)
				)
				(justify left bottom)
				(hide yes)
			)
		)
		(property "Description" "LED, Green, SMD, 0603, 20 mA, 1.7 V, 570 nm"
			(at 213.36 184.15 0)
			(effects
				(font
					(size 1.27 1.27)
				)
				(hide yes)
			)
		)
		(property "MPN" "LG L29K-G2J1-24-Z"
			(at 228.6 163.83 0)
			(effects
				(font
					(size 1.27 1.27)
					(thickness 0.15)
				)
				(justify left bottom)
				(hide yes)
			)
		)
		(property "Manufacturer" "OSRAM"
			(at 231.14 163.83 0)
			(effects
				(font
					(size 1.27 1.27)
					(thickness 0.15)
				)
				(justify left bottom)
				(hide yes)
			)
		)
		(property "Color" "Green"
			(at 215.9 182.8799 90)
			(effects
				(font
					(size 1.27 1.27)
				)
				(justify right)
			)
		)
		(property "Author" "Antmicro"
			(at 233.68 163.83 0)
			(effects
				(font
					(size 1.27 1.27)
					(thickness 0.15)
				)
				(justify left bottom)
				(hide yes)
			)
		)
		(property "License" "Apache-2.0"
			(at 236.22 163.83 0)
			(effects
				(font
					(size 1.27 1.27)
					(thickness 0.15)
				)
				(justify left bottom)
				(hide yes)
			)
		)
		(pin "2"
		)
		(pin "1"
		)
		(instances
			(project "usb-c-power-adapter"
				(path ""
					(reference "D9")
					(unit 1)
				)
			)
		)
	)
	(symbol
		(lib_id "antmicroResistors0402:R_3k16_0402")
		(at 128.27 236.22 90)
		(unit 1)
		(exclude_from_sim no)
		(in_bom yes)
		(on_board yes)
		(dnp no)
		(fields_autoplaced yes)
		(property "Reference" "R1"
			(at 130.81 232.41 90)
			(effects
				(font
					(size 1.27 1.27)
					(thickness 0.15)
				)
				(justify right)
			)
		)
		(property "Value" "R_3k16_0402"
			(at 140.97 215.9 0)
			(effects
				(font
					(size 1.27 1.27)
					(thickness 0.15)
				)
				(justify left bottom)
				(hide yes)
			)
		)
		(property "Footprint" "antmicro-footprints:R_0402_1005Metric"
			(at 143.51 215.9 0)
			(effects
				(font
					(size 1.27 1.27)
					(thickness 0.15)
				)
				(justify left bottom)
				(hide yes)
			)
		)
		(property "Datasheet" "https://www.mouser.com/datasheet/2/447/YAGEO_PYu_RC_Group_51_RoHS_L_12-3313492.pdf"
			(at 146.05 215.9 0)
			(effects
				(font
					(size 1.27 1.27)
					(thickness 0.15)
				)
				(justify left bottom)
				(hide yes)
			)
		)
		(property "Description" "SMD Chip Resistor, 3.16 kohm, ± 1%, 62.5 mW, 0402 [1005 Metric], Thick Film, General Purpose"
			(at 128.27 236.22 0)
			(effects
				(font
					(size 1.27 1.27)
				)
				(hide yes)
			)
		)
		(property "MPN" "RC0402FR-073K16L"
			(at 135.89 210.82 0)
			(effects
				(font
					(size 1.27 1.27)
					(thickness 0.15)
				)
				(justify left bottom)
				(hide yes)
			)
		)
		(property "Val" "3k16"
			(at 130.81 234.95 90)
			(effects
				(font
					(size 1.27 1.27)
					(thickness 0.15)
				)
				(justify right)
			)
		)
		(property "License" "Apache-2.0"
			(at 153.67 215.9 0)
			(effects
				(font
					(size 1.27 1.27)
					(thickness 0.15)
				)
				(justify left bottom)
				(hide yes)
			)
		)
		(property "Manufacturer" "YAGEO"
			(at 138.43 219.71 0)
			(effects
				(font
					(size 1.27 1.27)
					(thickness 0.15)
				)
				(justify left bottom)
				(hide yes)
			)
		)
		(property "Tolerance" "1%"
			(at 139.7 220.98 0)
			(effects
				(font
					(size 1.27 1.27)
					(thickness 0.15)
				)
				(justify left bottom)
				(hide yes)
			)
		)
		(property "Author" "Antmicro"
			(at 156.21 215.9 0)
			(effects
				(font
					(size 1.27 1.27)
					(thickness 0.15)
				)
				(justify left bottom)
				(hide yes)
			)
		)
		(pin "1"
		)
		(pin "2"
		)
		(instances
			(project "usb-c-power-adapter"
				(path ""
					(reference "R1")
					(unit 1)
				)
			)
		)
	)
	(symbol
		(lib_id "antmicroFixedInductors:L_3u3_2.5A_1008")
		(at 118.11 170.18 0)
		(unit 1)
		(exclude_from_sim no)
		(in_bom yes)
		(on_board yes)
		(dnp no)
		(fields_autoplaced yes)
		(property "Reference" "L2"
			(at 120.65 165.1 0)
			(effects
				(font
					(size 1.27 1.27)
					(thickness 0.15)
				)
			)
		)
		(property "Value" "L_3u3_2.5A_1008"
			(at 133.35 172.72 0)
			(effects
				(font
					(size 1.27 1.27)
					(thickness 0.15)
				)
				(justify left bottom)
				(hide yes)
			)
		)
		(property "Footprint" "antmicro-footprints:L_1008_2520Metric"
			(at 133.35 177.8 0)
			(effects
				(font
					(size 1.27 1.27)
					(thickness 0.15)
				)
				(justify left bottom)
				(hide yes)
			)
		)
		(property "Datasheet" "https://product.tdk.com/system/files/dam/doc/product/inductor/inductor/smd/catalog/inductor_automotive_power_tfm252012alma_en.pdf"
			(at 133.35 180.34 0)
			(effects
				(font
					(size 1.27 1.27)
					(thickness 0.15)
				)
				(justify left bottom)
				(hide yes)
			)
		)
		(property "Description" "3.3 µH Shielded Thin Film Inductor 2 A 140mOhm Max 1008 (2520 Metric)"
			(at 118.11 170.18 0)
			(effects
				(font
					(size 1.27 1.27)
				)
				(hide yes)
			)
		)
		(property "MPN" "TFM252012ALMA3R3MTAA"
			(at 133.35 182.88 0)
			(effects
				(font
					(size 1.27 1.27)
					(thickness 0.15)
				)
				(justify left bottom)
				(hide yes)
			)
		)
		(property "ISat" "2.1 A"
			(at 133.35 185.42 0)
			(effects
				(font
					(size 1.27 1.27)
					(thickness 0.15)
				)
				(justify left bottom)
				(hide yes)
			)
		)
		(property "IMax" "2.5 A"
			(at 133.35 187.96 0)
			(effects
				(font
					(size 1.27 1.27)
					(thickness 0.15)
				)
				(justify left bottom)
				(hide yes)
			)
		)
		(property "Manufacturer" "TDK"
			(at 133.35 190.5 0)
			(effects
				(font
					(size 1.27 1.27)
					(thickness 0.15)
				)
				(justify left bottom)
				(hide yes)
			)
		)
		(property "Val" "3u3/2.5A"
			(at 120.65 167.64 0)
			(effects
				(font
					(size 1.27 1.27)
					(thickness 0.15)
				)
			)
		)
		(property "Size" "2.5x2.0"
			(at 133.35 193.04 0)
			(effects
				(font
					(size 1.27 1.27)
				)
				(justify left bottom)
				(hide yes)
			)
		)
		(property "Author" "Antmicro"
			(at 133.35 195.58 0)
			(effects
				(font
					(size 1.27 1.27)
					(thickness 0.15)
				)
				(justify left bottom)
				(hide yes)
			)
		)
		(property "License" "Apache-2.0"
			(at 133.35 198.12 0)
			(effects
				(font
					(size 1.27 1.27)
					(thickness 0.15)
				)
				(justify left bottom)
				(hide yes)
			)
		)
		(pin "2"
		)
		(pin "1"
		)
		(instances
			(project "usb-c-power-adapter"
				(path ""
					(reference "L2")
					(unit 1)
				)
			)
		)
	)
	(symbol
		(lib_id "antmicroCapacitors0402:C_270p_25V_0402")
		(at 177.8 102.87 90)
		(mirror x)
		(unit 1)
		(exclude_from_sim no)
		(in_bom no)
		(on_board yes)
		(dnp yes)
		(fields_autoplaced yes)
		(property "Reference" "C13"
			(at 180.34 104.1462 90)
			(effects
				(font
					(size 1.27 1.27)
				)
				(justify right)
			)
		)
		(property "Value" "C_270p_25V_0402"
			(at 181.61 102.87 0)
			(effects
				(font
					(size 1.27 1.27)
				)
				(justify left)
				(hide yes)
			)
		)
		(property "Footprint" "antmicro-footprints:C_0402_1005Metric"
			(at 172.72 107.95 0)
			(effects
				(font
					(size 1.27 1.27)
					(thickness 0.15)
				)
				(justify left bottom)
				(hide yes)
			)
		)
		(property "Datasheet" "https://www.kemet.com/en/us/capacitors/product/C0402C271J3GAC7867.html"
			(at 177.8 102.87 0)
			(effects
				(font
					(size 1.27 1.27)
					(thickness 0.15)
				)
				(justify left bottom)
				(hide yes)
			)
		)
		(property "Description" "SMD Multilayer Ceramic Capacitor, 270 pF, 25 V, 0402 [1005 Metric], ± 5%, C0G / NP0"
			(at 177.8 102.87 0)
			(effects
				(font
					(size 1.27 1.27)
				)
				(hide yes)
			)
		)
		(property "Manufacturer" "KEMET"
			(at 167.64 107.95 0)
			(effects
				(font
					(size 1.27 1.27)
					(thickness 0.15)
				)
				(justify left bottom)
				(hide yes)
			)
		)
		(property "MPN" "C0402C271J3GAC7867"
			(at 170.18 107.95 0)
			(effects
				(font
					(size 1.27 1.27)
					(thickness 0.15)
				)
				(justify left bottom)
				(hide yes)
			)
		)
		(property "Val" "270p"
			(at 180.34 106.6863 90)
			(effects
				(font
					(size 1.27 1.27)
					(thickness 0.15)
				)
				(justify right)
			)
		)
		(property "License" "Apache-2.0"
			(at 200.66 123.19 0)
			(effects
				(font
					(size 1.27 1.27)
					(thickness 0.15)
				)
				(justify left bottom)
				(hide yes)
			)
		)
		(property "Author" "Antmicro"
			(at 203.2 123.19 0)
			(effects
				(font
					(size 1.27 1.27)
					(thickness 0.15)
				)
				(justify left bottom)
				(hide yes)
			)
		)
		(property "Voltage" "25V"
			(at 205.74 123.19 0)
			(effects
				(font
					(size 1.27 1.27)
				)
				(justify left bottom)
				(hide yes)
			)
		)
		(property "Dielectric" ""
			(at 208.28 123.19 0)
			(effects
				(font
					(size 1.27 1.27)
				)
				(justify left bottom)
				(hide yes)
			)
		)
		(pin "1"
		)
		(pin "2"
		)
		(instances
			(project "usb-c-power-adapter"
				(path ""
					(reference "C13")
					(unit 1)
				)
			)
		)
	)
	(symbol
		(lib_id "antmicroTestPoints:TP_0.75mm_SMD")
		(at 146.05 167.64 90)
		(unit 1)
		(exclude_from_sim no)
		(in_bom no)
		(on_board yes)
		(dnp no)
		(property "Reference" "TP5"
			(at 144.78 161.29 90)
			(effects
				(font
					(size 1.27 1.27)
					(thickness 0.15)
				)
				(justify right)
			)
		)
		(property "Value" "TP_0.75mm_SMD"
			(at 149.86 156.845 0)
			(effects
				(font
					(size 1.27 1.27)
					(thickness 0.15)
				)
				(justify left bottom)
				(hide yes)
			)
		)
		(property "Footprint" "antmicro-footprints:TP_SMD_0.75mm"
			(at 152.4 156.845 0)
			(effects
				(font
					(size 1.27 1.27)
					(thickness 0.15)
				)
				(justify left bottom)
				(hide yes)
			)
		)
		(property "Datasheet" ""
			(at 158.75 149.86 0)
			(effects
				(font
					(size 1.27 1.27)
					(thickness 0.15)
				)
				(justify left bottom)
				(hide yes)
			)
		)
		(property "Description" "SMT test point"
			(at 146.05 167.64 0)
			(effects
				(font
					(size 1.27 1.27)
				)
				(hide yes)
			)
		)
		(property "MPN" ""
			(at 157.48 156.845 0)
			(effects
				(font
					(size 1.27 1.27)
					(thickness 0.15)
				)
				(justify left bottom)
				(hide yes)
			)
		)
		(property "Manufacturer" ""
			(at 152.4 156.845 0)
			(effects
				(font
					(size 1.27 1.27)
					(thickness 0.15)
				)
				(justify left bottom)
				(hide yes)
			)
		)
		(property "Author" "Antmicro"
			(at 154.94 156.845 0)
			(effects
				(font
					(size 1.27 1.27)
					(thickness 0.15)
				)
				(justify left bottom)
				(hide yes)
			)
		)
		(property "License" "Apache-2.0"
			(at 157.48 156.845 0)
			(effects
				(font
					(size 1.27 1.27)
					(thickness 0.15)
				)
				(justify left bottom)
				(hide yes)
			)
		)
		(pin "1"
		)
		(instances
			(project "usb-c-power-adapter"
				(path ""
					(reference "TP5")
					(unit 1)
				)
			)
		)
	)
	(symbol
		(lib_id "antmicropower:+3V3")
		(at 153.67 224.79 0)
		(unit 1)
		(exclude_from_sim no)
		(in_bom yes)
		(on_board yes)
		(dnp no)
		(fields_autoplaced yes)
		(property "Reference" "#PWR069"
			(at 168.91 224.79 0)
			(effects
				(font
					(size 1.27 1.27)
					(thickness 0.15)
				)
				(justify left bottom)
				(hide yes)
			)
		)
		(property "Value" "+3V3"
			(at 153.67 219.71 0)
			(effects
				(font
					(size 1.27 1.27)
					(thickness 0.15)
				)
			)
		)
		(property "Footprint" ""
			(at 168.91 232.41 0)
			(effects
				(font
					(size 1.27 1.27)
					(thickness 0.15)
				)
				(justify left bottom)
				(hide yes)
			)
		)
		(property "Datasheet" ""
			(at 168.91 234.95 0)
			(effects
				(font
					(size 1.27 1.27)
					(thickness 0.15)
				)
				(justify left bottom)
				(hide yes)
			)
		)
		(property "Description" ""
			(at 153.67 224.79 0)
			(effects
				(font
					(size 1.27 1.27)
				)
				(hide yes)
			)
		)
		(property "Author" "Antmicro"
			(at 168.91 227.33 0)
			(effects
				(font
					(size 1.27 1.27)
					(thickness 0.15)
				)
				(justify left bottom)
				(hide yes)
			)
		)
		(property "License" "Apache-2.0"
			(at 168.91 229.87 0)
			(effects
				(font
					(size 1.27 1.27)
					(thickness 0.15)
				)
				(justify left bottom)
				(hide yes)
			)
		)
		(pin "1"
		)
		(instances
			(project "usb-c-power-adapter"
				(path ""
					(reference "#PWR069")
					(unit 1)
				)
			)
		)
	)
	(symbol
		(lib_id "antmicropower:+12V")
		(at 62.23 66.04 0)
		(unit 1)
		(exclude_from_sim no)
		(in_bom yes)
		(on_board yes)
		(dnp no)
		(fields_autoplaced yes)
		(property "Reference" "#PWR06"
			(at 62.23 69.85 0)
			(effects
				(font
					(size 1.27 1.27)
				)
				(hide yes)
			)
		)
		(property "Value" "+12V"
			(at 62.23 60.96 0)
			(effects
				(font
					(size 1.27 1.27)
				)
			)
		)
		(property "Footprint" ""
			(at 62.23 66.04 0)
			(effects
				(font
					(size 1.27 1.27)
				)
				(hide yes)
			)
		)
		(property "Datasheet" ""
			(at 62.23 66.04 0)
			(effects
				(font
					(size 1.27 1.27)
				)
				(hide yes)
			)
		)
		(property "Description" ""
			(at 62.23 66.04 0)
			(effects
				(font
					(size 1.27 1.27)
				)
				(hide yes)
			)
		)
		(pin "1"
		)
		(instances
			(project "usb-c-power-adapter"
				(path ""
					(reference "#PWR06")
					(unit 1)
				)
			)
		)
	)
	(symbol
		(lib_id "antmicropower:PWR_FLAG")
		(at 135.89 166.37 0)
		(unit 1)
		(exclude_from_sim no)
		(in_bom yes)
		(on_board yes)
		(dnp no)
		(fields_autoplaced yes)
		(property "Reference" "#FLG07"
			(at 135.89 164.465 0)
			(effects
				(font
					(size 1.27 1.27)
				)
				(hide yes)
			)
		)
		(property "Value" "PWR_FLAG"
			(at 135.89 161.29 0)
			(effects
				(font
					(size 1.27 1.27)
				)
			)
		)
		(property "Footprint" ""
			(at 135.89 166.37 0)
			(effects
				(font
					(size 1.27 1.27)
				)
				(hide yes)
			)
		)
		(property "Datasheet" ""
			(at 135.89 166.37 0)
			(effects
				(font
					(size 1.27 1.27)
				)
				(hide yes)
			)
		)
		(property "Description" ""
			(at 135.89 166.37 0)
			(effects
				(font
					(size 1.27 1.27)
				)
				(hide yes)
			)
		)
		(pin "1"
		)
		(instances
			(project "usb-c-power-adapter"
				(path ""
					(reference "#FLG07")
					(unit 1)
				)
			)
		)
	)
	(symbol
		(lib_id "antmicroResistors0402:R_220R_0402")
		(at 213.36 175.26 90)
		(unit 1)
		(exclude_from_sim no)
		(in_bom yes)
		(on_board yes)
		(dnp no)
		(fields_autoplaced yes)
		(property "Reference" "R30"
			(at 215.9 171.45 90)
			(effects
				(font
					(size 1.27 1.27)
					(thickness 0.15)
				)
				(justify right)
			)
		)
		(property "Value" "R_220R_0402"
			(at 226.06 154.94 0)
			(effects
				(font
					(size 1.27 1.27)
					(thickness 0.15)
				)
				(justify left bottom)
				(hide yes)
			)
		)
		(property "Footprint" "antmicro-footprints:R_0402_1005Metric"
			(at 228.6 154.94 0)
			(effects
				(font
					(size 1.27 1.27)
					(thickness 0.15)
				)
				(justify left bottom)
				(hide yes)
			)
		)
		(property "Datasheet" "https://www.bourns.com/docs/product-datasheets/cr.pdf"
			(at 231.14 154.94 0)
			(effects
				(font
					(size 1.27 1.27)
					(thickness 0.15)
				)
				(justify left bottom)
				(hide yes)
			)
		)
		(property "Description" "SMD Chip Resistor, 220 ohm, ± 1%, 62.5 mW, 0402 [1005 Metric], Thick Film, General Purpose"
			(at 213.36 175.26 0)
			(effects
				(font
					(size 1.27 1.27)
				)
				(hide yes)
			)
		)
		(property "MPN" "CR0402-FX-2200GLF"
			(at 233.68 154.94 0)
			(effects
				(font
					(size 1.27 1.27)
					(thickness 0.15)
				)
				(justify left bottom)
				(hide yes)
			)
		)
		(property "Manufacturer" "Bourns"
			(at 236.22 154.94 0)
			(effects
				(font
					(size 1.27 1.27)
					(thickness 0.15)
				)
				(justify left bottom)
				(hide yes)
			)
		)
		(property "License" "Apache-2.0"
			(at 238.76 154.94 0)
			(effects
				(font
					(size 1.27 1.27)
					(thickness 0.15)
				)
				(justify left bottom)
				(hide yes)
			)
		)
		(property "Author" "Antmicro"
			(at 241.3 154.94 0)
			(effects
				(font
					(size 1.27 1.27)
					(thickness 0.15)
				)
				(justify left bottom)
				(hide yes)
			)
		)
		(property "Val" "220R"
			(at 215.9 173.99 90)
			(effects
				(font
					(size 1.27 1.27)
					(thickness 0.15)
				)
				(justify right)
			)
		)
		(property "Tolerance" "1%"
			(at 223.52 154.94 0)
			(effects
				(font
					(size 1.27 1.27)
				)
				(justify left bottom)
				(hide yes)
			)
		)
		(pin "2"
		)
		(pin "1"
		)
		(instances
			(project "usb-c-power-adapter"
				(path ""
					(reference "R30")
					(unit 1)
				)
			)
		)
	)
	(symbol
		(lib_id "antmicroResistors0402:R_100k_0402")
		(at 106.68 81.28 90)
		(unit 1)
		(exclude_from_sim no)
		(in_bom yes)
		(on_board yes)
		(dnp no)
		(property "Reference" "R8"
			(at 108.712 77.4699 90)
			(effects
				(font
					(size 1.27 1.27)
				)
				(justify right)
			)
		)
		(property "Value" "R_100k_0402"
			(at 110.49 81.28 0)
			(effects
				(font
					(size 1.27 1.27)
				)
				(justify left)
				(hide yes)
			)
		)
		(property "Footprint" "antmicro-footprints:R_0402_1005Metric"
			(at 101.6 76.2 0)
			(effects
				(font
					(size 1.27 1.27)
					(thickness 0.15)
				)
				(justify left bottom)
				(hide yes)
			)
		)
		(property "Datasheet" "https://www.bourns.com/docs/product-datasheets/cr.pdf"
			(at 106.68 81.28 0)
			(effects
				(font
					(size 1.27 1.27)
					(thickness 0.15)
				)
				(justify left bottom)
				(hide yes)
			)
		)
		(property "Description" "SMD Chip Resistor, 100 kohm, ± 1%, 62.5 mW, 0402 [1005 Metric], Thick Film, General Purpose"
			(at 106.68 81.28 0)
			(effects
				(font
					(size 1.27 1.27)
				)
				(hide yes)
			)
		)
		(property "Manufacturer" "Bourns"
			(at 96.52 76.2 0)
			(effects
				(font
					(size 1.27 1.27)
					(thickness 0.15)
				)
				(justify left bottom)
				(hide yes)
			)
		)
		(property "MPN" "CR0402-FX-1003GLF"
			(at 99.06 76.2 0)
			(effects
				(font
					(size 1.27 1.27)
					(thickness 0.15)
				)
				(justify left bottom)
				(hide yes)
			)
		)
		(property "Val" "100k"
			(at 108.712 80.01 90)
			(effects
				(font
					(size 1.27 1.27)
					(thickness 0.15)
				)
				(justify right)
			)
		)
		(property "License" "Apache-2.0"
			(at 132.08 60.96 0)
			(effects
				(font
					(size 1.27 1.27)
					(thickness 0.15)
				)
				(justify left bottom)
				(hide yes)
			)
		)
		(property "Author" "Antmicro"
			(at 134.62 60.96 0)
			(effects
				(font
					(size 1.27 1.27)
					(thickness 0.15)
				)
				(justify left bottom)
				(hide yes)
			)
		)
		(property "Tolerance" "1%"
			(at 116.84 60.96 0)
			(effects
				(font
					(size 1.27 1.27)
				)
				(justify left bottom)
				(hide yes)
			)
		)
		(pin "1"
		)
		(pin "2"
		)
		(instances
			(project "usb-c-power-adapter"
				(path ""
					(reference "R8")
					(unit 1)
				)
			)
		)
	)
	(symbol
		(lib_id "antmicroCapacitorsmisc:C_47u_25V_1206")
		(at 295.91 91.44 90)
		(unit 1)
		(exclude_from_sim no)
		(in_bom yes)
		(on_board yes)
		(dnp no)
		(fields_autoplaced yes)
		(property "Reference" "C37"
			(at 298.45 86.3536 90)
			(effects
				(font
					(size 1.27 1.27)
					(thickness 0.15)
				)
				(justify right)
			)
		)
		(property "Value" "C_47u_25V_1206"
			(at 308.61 76.2 0)
			(effects
				(font
					(size 1.27 1.27)
					(thickness 0.15)
				)
				(justify left bottom)
				(hide yes)
			)
		)
		(property "Footprint" "antmicro-footprints:C_1206_3216Metric"
			(at 311.15 76.2 0)
			(effects
				(font
					(size 1.27 1.27)
					(thickness 0.15)
				)
				(justify left bottom)
				(hide yes)
			)
		)
		(property "Datasheet" "https://product.tdk.com/en/search/capacitor/ceramic/mlcc/info?part_no=C3216X5R1E476M160AC"
			(at 313.69 76.2 0)
			(effects
				(font
					(size 1.27 1.27)
					(thickness 0.15)
				)
				(justify left bottom)
				(hide yes)
			)
		)
		(property "Description" "SMD Multilayer Ceramic Capacitor, 47 µF, 25 V, 1206 [3216 Metric], ± 20%, X5R"
			(at 295.91 91.44 0)
			(effects
				(font
					(size 1.27 1.27)
				)
				(hide yes)
			)
		)
		(property "MPN" "C3216X5R1E476M160AC"
			(at 316.23 76.2 0)
			(effects
				(font
					(size 1.27 1.27)
					(thickness 0.15)
				)
				(justify left bottom)
				(hide yes)
			)
		)
		(property "Val" "47u"
			(at 298.45 88.8936 90)
			(effects
				(font
					(size 1.27 1.27)
					(thickness 0.15)
				)
				(justify right)
			)
		)
		(property "Voltage" "25V"
			(at 298.45 91.4336 90)
			(effects
				(font
					(size 1.27 1.27)
					(thickness 0.15)
				)
				(justify right)
			)
		)
		(property "Author" "Antmicro"
			(at 318.77 76.2 0)
			(effects
				(font
					(size 1.27 1.27)
					(thickness 0.15)
				)
				(justify left bottom)
				(hide yes)
			)
		)
		(property "License" "Apache-2.0"
			(at 321.31 76.2 0)
			(effects
				(font
					(size 1.27 1.27)
					(thickness 0.15)
				)
				(justify left bottom)
				(hide yes)
			)
		)
		(property "Manufacturer" "TDK"
			(at 323.85 76.2 0)
			(effects
				(font
					(size 1.27 1.27)
					(thickness 0.15)
				)
				(justify left bottom)
				(hide yes)
			)
		)
		(property "Dielectric" "X5R"
			(at 326.39 76.2 0)
			(effects
				(font
					(size 1.27 1.27)
					(thickness 0.15)
				)
				(justify left bottom)
				(hide yes)
			)
		)
		(property "Public" "False"
			(at 328.93 71.12 0)
			(effects
				(font
					(size 1.27 1.27)
				)
				(justify left bottom)
				(hide yes)
			)
		)
		(pin "2"
		)
		(pin "1"
		)
		(instances
			(project "usb-c-power-adapter"
				(path ""
					(reference "C37")
					(unit 1)
				)
			)
		)
	)
	(symbol
		(lib_id "antmicroResistors0402:R_470R_0402")
		(at 195.58 175.26 90)
		(unit 1)
		(exclude_from_sim no)
		(in_bom yes)
		(on_board yes)
		(dnp no)
		(fields_autoplaced yes)
		(property "Reference" "R29"
			(at 198.12 171.45 90)
			(effects
				(font
					(size 1.27 1.27)
					(thickness 0.15)
				)
				(justify right)
			)
		)
		(property "Value" "R_470_0402"
			(at 208.28 154.94 0)
			(effects
				(font
					(size 1.27 1.27)
					(thickness 0.15)
				)
				(justify left bottom)
				(hide yes)
			)
		)
		(property "Footprint" "antmicro-footprints:R_0402_1005Metric"
			(at 210.82 154.94 0)
			(effects
				(font
					(size 1.27 1.27)
					(thickness 0.15)
				)
				(justify left bottom)
				(hide yes)
			)
		)
		(property "Datasheet" "https://www.bourns.com/docs/product-datasheets/cr.pdf"
			(at 213.36 154.94 0)
			(effects
				(font
					(size 1.27 1.27)
					(thickness 0.15)
				)
				(justify left bottom)
				(hide yes)
			)
		)
		(property "Description" "SMD Chip Resistor, 470 ohm, ± 1%, 62.5 mW, 0402 [1005 Metric], Thick Film, General Purpose"
			(at 195.58 175.26 0)
			(effects
				(font
					(size 1.27 1.27)
				)
				(hide yes)
			)
		)
		(property "MPN" "CR0402-FX-4700GLF"
			(at 215.9 154.94 0)
			(effects
				(font
					(size 1.27 1.27)
					(thickness 0.15)
				)
				(justify left bottom)
				(hide yes)
			)
		)
		(property "Manufacturer" "Bourns"
			(at 218.44 154.94 0)
			(effects
				(font
					(size 1.27 1.27)
					(thickness 0.15)
				)
				(justify left bottom)
				(hide yes)
			)
		)
		(property "License" "Apache-2.0"
			(at 220.98 154.94 0)
			(effects
				(font
					(size 1.27 1.27)
					(thickness 0.15)
				)
				(justify left bottom)
				(hide yes)
			)
		)
		(property "Author" "Antmicro"
			(at 223.52 154.94 0)
			(effects
				(font
					(size 1.27 1.27)
					(thickness 0.15)
				)
				(justify left bottom)
				(hide yes)
			)
		)
		(property "Val" "470R"
			(at 198.12 173.99 90)
			(effects
				(font
					(size 1.27 1.27)
					(thickness 0.15)
				)
				(justify right)
			)
		)
		(property "Tolerance" "1%"
			(at 205.74 154.94 0)
			(effects
				(font
					(size 1.27 1.27)
				)
				(justify left bottom)
				(hide yes)
			)
		)
		(pin "2"
		)
		(pin "1"
		)
		(instances
			(project "usb-c-power-adapter"
				(path ""
					(reference "R29")
					(unit 1)
				)
			)
		)
	)
	(symbol
		(lib_id "antmicropower:GND")
		(at 128.27 191.77 0)
		(unit 1)
		(exclude_from_sim no)
		(in_bom yes)
		(on_board yes)
		(dnp no)
		(fields_autoplaced yes)
		(property "Reference" "#PWR041"
			(at 128.27 191.77 0)
			(effects
				(font
					(size 1.27 1.27)
				)
				(justify left)
				(hide yes)
			)
		)
		(property "Value" "GND"
			(at 128.27 196.215 0)
			(effects
				(font
					(size 1.27 1.27)
				)
			)
		)
		(property "Footprint" ""
			(at 128.27 191.77 0)
			(effects
				(font
					(size 1.27 1.27)
					(thickness 0.15)
				)
				(justify left bottom)
				(hide yes)
			)
		)
		(property "Datasheet" ""
			(at 128.27 191.77 0)
			(effects
				(font
					(size 1.27 1.27)
					(thickness 0.15)
				)
				(justify left bottom)
				(hide yes)
			)
		)
		(property "Description" ""
			(at 128.27 191.77 0)
			(effects
				(font
					(size 1.27 1.27)
				)
				(hide yes)
			)
		)
		(property "Author" "Antmicro"
			(at 137.16 199.39 0)
			(effects
				(font
					(size 1.27 1.27)
					(thickness 0.15)
				)
				(justify left bottom)
				(hide yes)
			)
		)
		(property "License" "Apache-2.0"
			(at 137.16 201.93 0)
			(effects
				(font
					(size 1.27 1.27)
					(thickness 0.15)
				)
				(justify left bottom)
				(hide yes)
			)
		)
		(pin "1"
		)
		(instances
			(project "usb-c-power-adapter"
				(path ""
					(reference "#PWR041")
					(unit 1)
				)
			)
		)
	)
	(symbol
		(lib_id "antmicropower:GND")
		(at 177.8 186.69 0)
		(unit 1)
		(exclude_from_sim no)
		(in_bom yes)
		(on_board yes)
		(dnp no)
		(fields_autoplaced yes)
		(property "Reference" "#PWR063"
			(at 186.69 189.23 0)
			(effects
				(font
					(size 1.27 1.27)
					(thickness 0.15)
				)
				(justify left bottom)
				(hide yes)
			)
		)
		(property "Value" "GND"
			(at 177.8 191.135 0)
			(effects
				(font
					(size 1.27 1.27)
					(thickness 0.15)
				)
			)
		)
		(property "Footprint" ""
			(at 186.69 194.31 0)
			(effects
				(font
					(size 1.27 1.27)
					(thickness 0.15)
				)
				(justify left bottom)
				(hide yes)
			)
		)
		(property "Datasheet" ""
			(at 186.69 199.39 0)
			(effects
				(font
					(size 1.27 1.27)
					(thickness 0.15)
				)
				(justify left bottom)
				(hide yes)
			)
		)
		(property "Description" ""
			(at 177.8 186.69 0)
			(effects
				(font
					(size 1.27 1.27)
				)
				(hide yes)
			)
		)
		(property "Author" "Antmicro"
			(at 186.69 194.31 0)
			(effects
				(font
					(size 1.27 1.27)
					(thickness 0.15)
				)
				(justify left bottom)
				(hide yes)
			)
		)
		(property "License" "Apache-2.0"
			(at 186.69 196.85 0)
			(effects
				(font
					(size 1.27 1.27)
					(thickness 0.15)
				)
				(justify left bottom)
				(hide yes)
			)
		)
		(pin "1"
		)
		(instances
			(project "usb-c-power-adapter"
				(path ""
					(reference "#PWR063")
					(unit 1)
				)
			)
		)
	)
	(symbol
		(lib_id "antmicroResistors0402:R_100k_0402")
		(at 68.58 175.26 180)
		(unit 1)
		(exclude_from_sim no)
		(in_bom yes)
		(on_board yes)
		(dnp no)
		(property "Reference" "R10"
			(at 65.786 171.196 0)
			(effects
				(font
					(size 1.27 1.27)
					(thickness 0.15)
				)
			)
		)
		(property "Value" "R_100k_0402"
			(at 48.26 162.56 0)
			(effects
				(font
					(size 1.27 1.27)
					(thickness 0.15)
				)
				(justify left bottom)
				(hide yes)
			)
		)
		(property "Footprint" "antmicro-footprints:R_0402_1005Metric"
			(at 48.26 160.02 0)
			(effects
				(font
					(size 1.27 1.27)
					(thickness 0.15)
				)
				(justify left bottom)
				(hide yes)
			)
		)
		(property "Datasheet" "https://www.bourns.com/docs/product-datasheets/cr.pdf"
			(at 48.26 157.48 0)
			(effects
				(font
					(size 1.27 1.27)
					(thickness 0.15)
				)
				(justify left bottom)
				(hide yes)
			)
		)
		(property "Description" "SMD Chip Resistor, 100 kohm, ± 1%, 62.5 mW, 0402 [1005 Metric], Thick Film, General Purpose"
			(at 68.58 175.26 0)
			(effects
				(font
					(size 1.27 1.27)
				)
				(hide yes)
			)
		)
		(property "MPN" "CR0402-FX-1003GLF"
			(at 48.26 154.94 0)
			(effects
				(font
					(size 1.27 1.27)
					(thickness 0.15)
				)
				(justify left bottom)
				(hide yes)
			)
		)
		(property "Manufacturer" "Bourns"
			(at 48.26 152.4 0)
			(effects
				(font
					(size 1.27 1.27)
					(thickness 0.15)
				)
				(justify left bottom)
				(hide yes)
			)
		)
		(property "License" "Apache-2.0"
			(at 48.26 149.86 0)
			(effects
				(font
					(size 1.27 1.27)
					(thickness 0.15)
				)
				(justify left bottom)
				(hide yes)
			)
		)
		(property "Author" "Antmicro"
			(at 48.26 147.32 0)
			(effects
				(font
					(size 1.27 1.27)
					(thickness 0.15)
				)
				(justify left bottom)
				(hide yes)
			)
		)
		(property "Val" "100k"
			(at 66.04 173.228 0)
			(effects
				(font
					(size 1.27 1.27)
					(thickness 0.15)
				)
			)
		)
		(property "Tolerance" "1%"
			(at 48.26 165.1 0)
			(effects
				(font
					(size 1.27 1.27)
				)
				(justify left bottom)
				(hide yes)
			)
		)
		(pin "1"
		)
		(pin "2"
		)
		(instances
			(project "usb-c-power-adapter"
				(path ""
					(reference "R10")
					(unit 1)
				)
			)
		)
	)
	(symbol
		(lib_id "antmicropower:GND")
		(at 304.8 78.74 0)
		(mirror y)
		(unit 1)
		(exclude_from_sim no)
		(in_bom yes)
		(on_board yes)
		(dnp no)
		(fields_autoplaced yes)
		(property "Reference" "#PWR022"
			(at 304.8 78.74 0)
			(effects
				(font
					(size 1.27 1.27)
				)
				(justify left)
				(hide yes)
			)
		)
		(property "Value" "GND"
			(at 304.8 83.185 0)
			(effects
				(font
					(size 1.27 1.27)
				)
			)
		)
		(property "Footprint" ""
			(at 304.8 78.74 0)
			(effects
				(font
					(size 1.27 1.27)
					(thickness 0.15)
				)
				(justify left bottom)
				(hide yes)
			)
		)
		(property "Datasheet" ""
			(at 304.8 78.74 0)
			(effects
				(font
					(size 1.27 1.27)
					(thickness 0.15)
				)
				(justify left bottom)
				(hide yes)
			)
		)
		(property "Description" ""
			(at 304.8 78.74 0)
			(effects
				(font
					(size 1.27 1.27)
				)
				(hide yes)
			)
		)
		(property "Author" "Antmicro"
			(at 295.91 86.36 0)
			(effects
				(font
					(size 1.27 1.27)
					(thickness 0.15)
				)
				(justify left bottom)
				(hide yes)
			)
		)
		(property "License" "Apache-2.0"
			(at 295.91 88.9 0)
			(effects
				(font
					(size 1.27 1.27)
					(thickness 0.15)
				)
				(justify left bottom)
				(hide yes)
			)
		)
		(pin "1"
		)
		(instances
			(project "usb-c-power-adapter"
				(path ""
					(reference "#PWR022")
					(unit 1)
				)
			)
		)
	)
	(symbol
		(lib_id "antmicroWire2BoardConnectors:JST_SH_1x4_SM04B-SRSS-TB-LF-SN")
		(at 363.22 93.98 0)
		(mirror y)
		(unit 1)
		(exclude_from_sim no)
		(in_bom yes)
		(on_board yes)
		(dnp no)
		(property "Reference" "J3"
			(at 352.806 99.06 0)
			(effects
				(font
					(size 1.27 1.27)
					(thickness 0.15)
				)
			)
		)
		(property "Value" "JST_SH_1x4_SM04B-SRSS-TB-LF-SN"
			(at 336.55 101.6 0)
			(effects
				(font
					(size 1.27 1.27)
					(thickness 0.15)
				)
				(justify left bottom)
				(hide yes)
			)
		)
		(property "Footprint" "antmicro-footprints:Conn_JST_SH_1x4_SM04B-SRSS-TB-LF-SN"
			(at 336.55 104.14 0)
			(effects
				(font
					(size 1.27 1.27)
					(thickness 0.15)
				)
				(justify left bottom)
				(hide yes)
			)
		)
		(property "Datasheet" "https://www.jst-mfg.com/product/pdf/eng/eSH.pdf"
			(at 336.55 106.68 0)
			(effects
				(font
					(size 1.27 1.27)
					(thickness 0.15)
				)
				(justify left bottom)
				(hide yes)
			)
		)
		(property "Description" "Pin Header, Right Angle, Wire-to-Board, 1 mm, 1 Rows, 4 Contacts, Surface Mount Right Angle, SH"
			(at 363.22 93.98 0)
			(effects
				(font
					(size 1.27 1.27)
				)
				(hide yes)
			)
		)
		(property "MPN" "SM04B-SRSS-TB(LF)(SN)"
			(at 355.6 99.568 90)
			(effects
				(font
					(size 1.27 1.27)
					(thickness 0.15)
				)
			)
		)
		(property "Manufacturer" "JST Automotive Connectors"
			(at 336.55 109.22 0)
			(effects
				(font
					(size 1.27 1.27)
					(thickness 0.15)
				)
				(justify left bottom)
				(hide yes)
			)
		)
		(property "Author" "Antmicro"
			(at 336.55 111.76 0)
			(effects
				(font
					(size 1.27 1.27)
					(thickness 0.15)
				)
				(justify left bottom)
				(hide yes)
			)
		)
		(property "License" "Apache-2.0"
			(at 336.55 114.3 0)
			(effects
				(font
					(size 1.27 1.27)
					(thickness 0.15)
				)
				(justify left bottom)
				(hide yes)
			)
		)
		(pin "1"
		)
		(pin "4"
		)
		(pin "MP"
		)
		(pin "2"
		)
		(pin "3"
		)
		(instances
			(project "usb-c-power-adapter"
				(path ""
					(reference "J3")
					(unit 1)
				)
			)
		)
	)
	(symbol
		(lib_id "antmicroDCDCConverters:SIC477ED-T1-GE3")
		(at 115.57 80.01 0)
		(unit 1)
		(exclude_from_sim no)
		(in_bom yes)
		(on_board yes)
		(dnp no)
		(fields_autoplaced yes)
		(property "Reference" "U2"
			(at 129.54 72.39 0)
			(effects
				(font
					(size 1.27 1.27)
					(thickness 0.15)
				)
			)
		)
		(property "Value" "SIC477ED-T1-GE3"
			(at 129.54 113.665 0)
			(effects
				(font
					(size 1.27 1.27)
					(thickness 0.15)
				)
				(hide yes)
			)
		)
		(property "Footprint" "antmicro-footprints:SIC47XED-T1-GE3"
			(at 166.37 90.17 0)
			(effects
				(font
					(size 1.27 1.27)
					(thickness 0.15)
				)
				(justify left bottom)
				(hide yes)
			)
		)
		(property "Datasheet" "https://www.vishay.com/docs/77113/sic47x.pdf"
			(at 166.37 92.71 0)
			(effects
				(font
					(size 1.27 1.27)
					(thickness 0.15)
				)
				(justify left bottom)
				(hide yes)
			)
		)
		(property "Description" "DC/DC Synchronous Regulator, Adjustable, 4.5V to 55VIn, 0.8V to 50.6V/6AOut, 2MHz, PowerPAK MLP55-27"
			(at 115.57 80.01 0)
			(effects
				(font
					(size 1.27 1.27)
				)
				(hide yes)
			)
		)
		(property "Manufacturer" "Vishay"
			(at 166.37 95.25 0)
			(effects
				(font
					(size 1.27 1.27)
					(thickness 0.15)
				)
				(justify left bottom)
				(hide yes)
			)
		)
		(property "MPN" "SIC477ED-T1-GE3"
			(at 129.54 74.93 0)
			(effects
				(font
					(size 1.27 1.27)
					(thickness 0.15)
				)
			)
		)
		(property "Author" "Antmicro"
			(at 166.37 100.33 0)
			(effects
				(font
					(size 1.27 1.27)
					(thickness 0.15)
				)
				(justify left bottom)
				(hide yes)
			)
		)
		(property "License" "Apache-2.0"
			(at 166.37 102.87 0)
			(effects
				(font
					(size 1.27 1.27)
					(thickness 0.15)
				)
				(justify left bottom)
				(hide yes)
			)
		)
		(pin "1"
		)
		(pin "10"
		)
		(pin "11"
		)
		(pin "12"
		)
		(pin "13"
		)
		(pin "14"
		)
		(pin "15"
		)
		(pin "16"
		)
		(pin "17"
		)
		(pin "18"
		)
		(pin "19"
		)
		(pin "2"
		)
		(pin "20"
		)
		(pin "21"
		)
		(pin "22"
		)
		(pin "23"
		)
		(pin "24"
		)
		(pin "25"
		)
		(pin "26"
		)
		(pin "27"
		)
		(pin "28"
		)
		(pin "3"
		)
		(pin "4"
		)
		(pin "5"
		)
		(pin "6"
		)
		(pin "7"
		)
		(pin "8"
		)
		(pin "9"
		)
		(instances
			(project "usb-c-power-adapter"
				(path ""
					(reference "U2")
					(unit 1)
				)
			)
		)
	)
	(symbol
		(lib_id "antmicropower:+12V")
		(at 234.95 71.12 0)
		(unit 1)
		(exclude_from_sim no)
		(in_bom yes)
		(on_board yes)
		(dnp no)
		(property "Reference" "#PWR034"
			(at 234.95 74.93 0)
			(effects
				(font
					(size 1.27 1.27)
				)
				(hide yes)
			)
		)
		(property "Value" "+12V"
			(at 235.585 66.04 0)
			(effects
				(font
					(size 1.27 1.27)
				)
			)
		)
		(property "Footprint" ""
			(at 234.95 71.12 0)
			(effects
				(font
					(size 1.27 1.27)
				)
				(hide yes)
			)
		)
		(property "Datasheet" ""
			(at 234.95 71.12 0)
			(effects
				(font
					(size 1.27 1.27)
				)
				(hide yes)
			)
		)
		(property "Description" ""
			(at 234.95 71.12 0)
			(effects
				(font
					(size 1.27 1.27)
				)
				(hide yes)
			)
		)
		(pin "1"
		)
		(instances
			(project "usb-c-power-adapter"
				(path ""
					(reference "#PWR034")
					(unit 1)
				)
			)
		)
	)
	(symbol
		(lib_id "antmicroCapacitorsmisc:C_22u_25V_0805")
		(at 278.13 62.23 90)
		(unit 1)
		(exclude_from_sim no)
		(in_bom yes)
		(on_board yes)
		(dnp no)
		(fields_autoplaced yes)
		(property "Reference" "C29"
			(at 280.67 57.1436 90)
			(effects
				(font
					(size 1.27 1.27)
					(thickness 0.15)
				)
				(justify right)
			)
		)
		(property "Value" "C_22u_25V_0805"
			(at 288.29 41.91 0)
			(effects
				(font
					(size 1.27 1.27)
					(thickness 0.15)
				)
				(justify left bottom)
				(hide yes)
			)
		)
		(property "Footprint" "antmicro-footprints:C_0805_2012Metric"
			(at 290.83 41.91 0)
			(effects
				(font
					(size 1.27 1.27)
					(thickness 0.15)
				)
				(justify left bottom)
				(hide yes)
			)
		)
		(property "Datasheet" "https://product.samsungsem.com/mlcc/CL21A226MAYNNN.do"
			(at 293.37 41.91 0)
			(effects
				(font
					(size 1.27 1.27)
					(thickness 0.15)
				)
				(justify left bottom)
				(hide yes)
			)
		)
		(property "Description" "SMT Multilayer Ceramic Capacitor, 22uF, +/-20%, 25V, X5R, 0805 [2012 Metric]"
			(at 278.13 62.23 0)
			(effects
				(font
					(size 1.27 1.27)
				)
				(hide yes)
			)
		)
		(property "MPN" "CL21A226MAYNNNE"
			(at 295.91 41.91 0)
			(effects
				(font
					(size 1.27 1.27)
					(thickness 0.15)
				)
				(justify left bottom)
				(hide yes)
			)
		)
		(property "Manufacturer" "Samsung Electro-Mechanics"
			(at 298.45 41.91 0)
			(effects
				(font
					(size 1.27 1.27)
					(thickness 0.15)
				)
				(justify left bottom)
				(hide yes)
			)
		)
		(property "License" "Apache-2.0"
			(at 300.99 41.91 0)
			(effects
				(font
					(size 1.27 1.27)
					(thickness 0.15)
				)
				(justify left bottom)
				(hide yes)
			)
		)
		(property "Author" "Antmicro"
			(at 303.53 41.91 0)
			(effects
				(font
					(size 1.27 1.27)
					(thickness 0.15)
				)
				(justify left bottom)
				(hide yes)
			)
		)
		(property "Val" "22u"
			(at 280.67 59.6836 90)
			(effects
				(font
					(size 1.27 1.27)
					(thickness 0.15)
				)
				(justify right)
			)
		)
		(property "Voltage" "25V"
			(at 280.67 62.2235 90)
			(effects
				(font
					(size 1.27 1.27)
				)
				(justify right)
			)
		)
		(property "Dielectric" "X5R"
			(at 308.61 41.91 0)
			(effects
				(font
					(size 1.27 1.27)
				)
				(justify left bottom)
				(hide yes)
			)
		)
		(property "Public" "False"
			(at 311.15 41.91 0)
			(effects
				(font
					(size 1.27 1.27)
				)
				(justify left bottom)
				(hide yes)
			)
		)
		(pin "1"
		)
		(pin "2"
		)
		(instances
			(project "usb-c-power-adapter"
				(path ""
					(reference "C29")
					(unit 1)
				)
			)
		)
	)
	(symbol
		(lib_id "antmicropower:GND")
		(at 99.06 116.84 0)
		(unit 1)
		(exclude_from_sim no)
		(in_bom yes)
		(on_board yes)
		(dnp no)
		(fields_autoplaced yes)
		(property "Reference" "#PWR013"
			(at 99.06 116.84 0)
			(effects
				(font
					(size 1.27 1.27)
				)
				(justify left)
				(hide yes)
			)
		)
		(property "Value" "GND"
			(at 99.06 121.285 0)
			(effects
				(font
					(size 1.27 1.27)
				)
			)
		)
		(property "Footprint" ""
			(at 99.06 116.84 0)
			(effects
				(font
					(size 1.27 1.27)
					(thickness 0.15)
				)
				(justify left bottom)
				(hide yes)
			)
		)
		(property "Datasheet" ""
			(at 99.06 116.84 0)
			(effects
				(font
					(size 1.27 1.27)
					(thickness 0.15)
				)
				(justify left bottom)
				(hide yes)
			)
		)
		(property "Description" ""
			(at 99.06 116.84 0)
			(effects
				(font
					(size 1.27 1.27)
				)
				(hide yes)
			)
		)
		(property "Author" "Antmicro"
			(at 107.95 124.46 0)
			(effects
				(font
					(size 1.27 1.27)
					(thickness 0.15)
				)
				(justify left bottom)
				(hide yes)
			)
		)
		(property "License" "Apache-2.0"
			(at 107.95 127 0)
			(effects
				(font
					(size 1.27 1.27)
					(thickness 0.15)
				)
				(justify left bottom)
				(hide yes)
			)
		)
		(pin "1"
		)
		(instances
			(project "usb-c-power-adapter"
				(path ""
					(reference "#PWR013")
					(unit 1)
				)
			)
		)
	)
	(symbol
		(lib_id "antmicroCapacitors0603:C_10u_25V_0603")
		(at 50.8 241.3 90)
		(unit 1)
		(exclude_from_sim no)
		(in_bom yes)
		(on_board yes)
		(dnp no)
		(fields_autoplaced yes)
		(property "Reference" "C22"
			(at 53.34 237.4836 90)
			(effects
				(font
					(size 1.27 1.27)
					(thickness 0.15)
				)
				(justify right)
			)
		)
		(property "Value" "C_10u_25V_0603"
			(at 60.96 220.98 0)
			(effects
				(font
					(size 1.27 1.27)
					(thickness 0.15)
				)
				(justify left bottom)
				(hide yes)
			)
		)
		(property "Footprint" "antmicro-footprints:C_0603_1608Metric"
			(at 63.5 220.98 0)
			(effects
				(font
					(size 1.27 1.27)
					(thickness 0.15)
				)
				(justify left bottom)
				(hide yes)
			)
		)
		(property "Datasheet" "https://product.tdk.com/en/search/capacitor/ceramic/mlcc/info?part_no=C1608X5R1E106M080AC"
			(at 66.04 220.98 0)
			(effects
				(font
					(size 1.27 1.27)
					(thickness 0.15)
				)
				(justify left bottom)
				(hide yes)
			)
		)
		(property "Description" "SMD Multilayer Ceramic Capacitor, 10 µF, 25 V, 0603 [1608 Metric], ± 20%, X5R, C"
			(at 50.8 241.3 0)
			(effects
				(font
					(size 1.27 1.27)
				)
				(hide yes)
			)
		)
		(property "MPN" "C1608X5R1E106M080AC"
			(at 68.58 220.98 0)
			(effects
				(font
					(size 1.27 1.27)
					(thickness 0.15)
				)
				(justify left bottom)
				(hide yes)
			)
		)
		(property "Manufacturer" "TDK"
			(at 71.12 220.98 0)
			(effects
				(font
					(size 1.27 1.27)
					(thickness 0.15)
				)
				(justify left bottom)
				(hide yes)
			)
		)
		(property "License" "Apache-2.0"
			(at 73.66 220.98 0)
			(effects
				(font
					(size 1.27 1.27)
					(thickness 0.15)
				)
				(justify left bottom)
				(hide yes)
			)
		)
		(property "Author" "Antmicro"
			(at 76.2 220.98 0)
			(effects
				(font
					(size 1.27 1.27)
					(thickness 0.15)
				)
				(justify left bottom)
				(hide yes)
			)
		)
		(property "Val" "10u"
			(at 53.34 240.0236 90)
			(effects
				(font
					(size 1.27 1.27)
					(thickness 0.15)
				)
				(justify right)
			)
		)
		(property "Voltage" "25V"
			(at 78.74 220.98 0)
			(effects
				(font
					(size 1.27 1.27)
				)
				(justify left bottom)
				(hide yes)
			)
		)
		(property "Dielectric" ""
			(at 81.28 220.98 0)
			(effects
				(font
					(size 1.27 1.27)
				)
				(justify left bottom)
				(hide yes)
			)
		)
		(pin "1"
		)
		(pin "2"
		)
		(instances
			(project "usb-c-power-adapter"
				(path ""
					(reference "C22")
					(unit 1)
				)
			)
		)
	)
	(symbol
		(lib_id "antmicroCapacitors0402:C_1u_25V_0402")
		(at 382.27 101.6 90)
		(unit 1)
		(exclude_from_sim no)
		(in_bom yes)
		(on_board yes)
		(dnp no)
		(fields_autoplaced yes)
		(property "Reference" "C41"
			(at 384.81 97.7836 90)
			(effects
				(font
					(size 1.27 1.27)
					(thickness 0.15)
				)
				(justify right)
			)
		)
		(property "Value" "C_1u_25V_0402"
			(at 392.43 81.28 0)
			(effects
				(font
					(size 1.27 1.27)
					(thickness 0.15)
				)
				(justify left bottom)
				(hide yes)
			)
		)
		(property "Footprint" "antmicro-footprints:C_0402_1005Metric"
			(at 394.97 81.28 0)
			(effects
				(font
					(size 1.27 1.27)
					(thickness 0.15)
				)
				(justify left bottom)
				(hide yes)
			)
		)
		(property "Datasheet" "https://www.murata.com/products/productdetail?partno=GRM155R61E105KE11%23"
			(at 397.51 81.28 0)
			(effects
				(font
					(size 1.27 1.27)
					(thickness 0.15)
				)
				(justify left bottom)
				(hide yes)
			)
		)
		(property "Description" "SMD Multilayer Ceramic Capacitor, 1 µF, 25 V, 0402 [1005 Metric], ± 10%, X5R, GRM Series"
			(at 382.27 101.6 0)
			(effects
				(font
					(size 1.27 1.27)
				)
				(hide yes)
			)
		)
		(property "MPN" "GRM155R61E105KE11J"
			(at 400.05 81.28 0)
			(effects
				(font
					(size 1.27 1.27)
					(thickness 0.15)
				)
				(justify left bottom)
				(hide yes)
			)
		)
		(property "Manufacturer" "Murata"
			(at 402.59 81.28 0)
			(effects
				(font
					(size 1.27 1.27)
					(thickness 0.15)
				)
				(justify left bottom)
				(hide yes)
			)
		)
		(property "License" "Apache-2.0"
			(at 405.13 81.28 0)
			(effects
				(font
					(size 1.27 1.27)
					(thickness 0.15)
				)
				(justify left bottom)
				(hide yes)
			)
		)
		(property "Author" "Antmicro"
			(at 407.67 81.28 0)
			(effects
				(font
					(size 1.27 1.27)
					(thickness 0.15)
				)
				(justify left bottom)
				(hide yes)
			)
		)
		(property "Val" "1u"
			(at 384.81 100.3236 90)
			(effects
				(font
					(size 1.27 1.27)
					(thickness 0.15)
				)
				(justify right)
			)
		)
		(property "Voltage" "25V"
			(at 410.21 81.28 0)
			(effects
				(font
					(size 1.27 1.27)
				)
				(justify left bottom)
				(hide yes)
			)
		)
		(property "Dielectric" "X5R"
			(at 412.75 81.28 0)
			(effects
				(font
					(size 1.27 1.27)
				)
				(justify left bottom)
				(hide yes)
			)
		)
		(pin "2"
		)
		(pin "1"
		)
		(instances
			(project "usb-c-power-adapter"
				(path ""
					(reference "C41")
					(unit 1)
				)
			)
		)
	)
	(symbol
		(lib_id "antmicropower:+12V")
		(at 177.8 167.64 0)
		(unit 1)
		(exclude_from_sim no)
		(in_bom yes)
		(on_board yes)
		(dnp no)
		(property "Reference" "#PWR062"
			(at 177.8 171.45 0)
			(effects
				(font
					(size 1.27 1.27)
				)
				(hide yes)
			)
		)
		(property "Value" "+12V"
			(at 177.8 163.195 0)
			(effects
				(font
					(size 1.27 1.27)
				)
			)
		)
		(property "Footprint" ""
			(at 177.8 167.64 0)
			(effects
				(font
					(size 1.27 1.27)
				)
				(hide yes)
			)
		)
		(property "Datasheet" ""
			(at 177.8 167.64 0)
			(effects
				(font
					(size 1.27 1.27)
				)
				(hide yes)
			)
		)
		(property "Description" ""
			(at 177.8 167.64 0)
			(effects
				(font
					(size 1.27 1.27)
				)
				(hide yes)
			)
		)
		(pin "1"
		)
		(instances
			(project "usb-c-power-adapter"
				(path ""
					(reference "#PWR062")
					(unit 1)
				)
			)
		)
	)
	(symbol
		(lib_id "antmicroFerriteBeadsandChips:FB_10Z_10A_WE-MPSB_1206")
		(at 39.37 67.31 0)
		(unit 1)
		(exclude_from_sim no)
		(in_bom no)
		(on_board yes)
		(dnp yes)
		(fields_autoplaced yes)
		(property "Reference" "FB2"
			(at 41.8719 60.96 0)
			(effects
				(font
					(size 1.27 1.27)
					(thickness 0.15)
				)
			)
		)
		(property "Value" "FB_10Z_10A_WE-MPSB_1206"
			(at 53.34 69.85 0)
			(effects
				(font
					(size 1.27 1.27)
					(thickness 0.15)
				)
				(justify left bottom)
				(hide yes)
			)
		)
		(property "Footprint" "antmicro-footprints:FB_1206_3216Metric"
			(at 53.34 74.93 0)
			(effects
				(font
					(size 1.27 1.27)
					(thickness 0.15)
				)
				(justify left bottom)
				(hide yes)
			)
		)
		(property "Datasheet" "https://www.we-online.com/catalog/datasheet/74279221100.pdf"
			(at 53.34 77.47 0)
			(effects
				(font
					(size 1.27 1.27)
					(thickness 0.15)
				)
				(justify left bottom)
				(hide yes)
			)
		)
		(property "Description" "Ferrite Bead, 1206 [3216 Metric], 10 ohm, 10.5 A, WE-MPSB, 0.003 ohm, ± 25%, High Current"
			(at 39.37 67.31 0)
			(effects
				(font
					(size 1.27 1.27)
				)
				(hide yes)
			)
		)
		(property "Val" "10Z/10A"
			(at 41.8719 63.5 0)
			(effects
				(font
					(size 1.27 1.27)
				)
			)
		)
		(property "MPN" "74279221100"
			(at 53.34 80.01 0)
			(effects
				(font
					(size 1.27 1.27)
					(thickness 0.15)
				)
				(justify left bottom)
				(hide yes)
			)
		)
		(property "Manufacturer" "Würth Elektronik"
			(at 53.34 82.55 0)
			(effects
				(font
					(size 1.27 1.27)
					(thickness 0.15)
				)
				(justify left bottom)
				(hide yes)
			)
		)
		(property "Current" ""
			(at 59.69 90.17 0)
			(effects
				(font
					(size 1.27 1.27)
					(thickness 0.15)
				)
				(justify left bottom)
				(hide yes)
			)
		)
		(property "Author" "Antmicro"
			(at 53.34 85.09 0)
			(effects
				(font
					(size 1.27 1.27)
					(thickness 0.15)
				)
				(justify left bottom)
				(hide yes)
			)
		)
		(property "License" "Apache-2.0"
			(at 53.34 87.63 0)
			(effects
				(font
					(size 1.27 1.27)
					(thickness 0.15)
				)
				(justify left bottom)
				(hide yes)
			)
		)
		(pin "2"
		)
		(pin "1"
		)
		(instances
			(project "usb-c-power-adapter"
				(path ""
					(reference "FB2")
					(unit 1)
				)
			)
		)
	)
	(symbol
		(lib_id "antmicroResistors0402:R_68k_0402")
		(at 99.06 115.57 90)
		(unit 1)
		(exclude_from_sim no)
		(in_bom no)
		(on_board yes)
		(dnp yes)
		(fields_autoplaced yes)
		(property "Reference" "R7"
			(at 101.6 111.76 90)
			(effects
				(font
					(size 1.27 1.27)
					(thickness 0.15)
				)
				(justify right)
			)
		)
		(property "Value" "R_68k_0402"
			(at 111.76 95.25 0)
			(effects
				(font
					(size 1.27 1.27)
					(thickness 0.15)
				)
				(justify left bottom)
				(hide yes)
			)
		)
		(property "Footprint" "antmicro-footprints:R_0402_1005Metric"
			(at 114.3 95.25 0)
			(effects
				(font
					(size 1.27 1.27)
					(thickness 0.15)
				)
				(justify left bottom)
				(hide yes)
			)
		)
		(property "Datasheet" "https://www.bourns.com/docs/product-datasheets/cr.pdf"
			(at 116.84 95.25 0)
			(effects
				(font
					(size 1.27 1.27)
					(thickness 0.15)
				)
				(justify left bottom)
				(hide yes)
			)
		)
		(property "Description" "SMD Chip Resistor"
			(at 99.06 115.57 0)
			(effects
				(font
					(size 1.27 1.27)
				)
				(hide yes)
			)
		)
		(property "MPN" "CR0402-FX-6802GLF"
			(at 119.38 95.25 0)
			(effects
				(font
					(size 1.27 1.27)
					(thickness 0.15)
				)
				(justify left bottom)
				(hide yes)
			)
		)
		(property "Manufacturer" "Bourns"
			(at 121.92 95.25 0)
			(effects
				(font
					(size 1.27 1.27)
					(thickness 0.15)
				)
				(justify left bottom)
				(hide yes)
			)
		)
		(property "License" "Apache-2.0"
			(at 124.46 95.25 0)
			(effects
				(font
					(size 1.27 1.27)
					(thickness 0.15)
				)
				(justify left bottom)
				(hide yes)
			)
		)
		(property "Author" "Antmicro"
			(at 127 95.25 0)
			(effects
				(font
					(size 1.27 1.27)
					(thickness 0.15)
				)
				(justify left bottom)
				(hide yes)
			)
		)
		(property "Val" "68k"
			(at 101.6 114.3 90)
			(effects
				(font
					(size 1.27 1.27)
					(thickness 0.15)
				)
				(justify right)
			)
		)
		(property "Tolerance" "1%"
			(at 109.22 95.25 0)
			(effects
				(font
					(size 1.27 1.27)
				)
				(justify left bottom)
				(hide yes)
			)
		)
		(pin "1"
		)
		(pin "2"
		)
		(instances
			(project "usb-c-power-adapter"
				(path ""
					(reference "R7")
					(unit 1)
				)
			)
		)
	)
	(symbol
		(lib_id "antmicropower:GND")
		(at 369.57 63.5 0)
		(unit 1)
		(exclude_from_sim no)
		(in_bom yes)
		(on_board yes)
		(dnp no)
		(fields_autoplaced yes)
		(property "Reference" "#PWR029"
			(at 378.46 66.04 0)
			(effects
				(font
					(size 1.27 1.27)
					(thickness 0.15)
				)
				(justify left bottom)
				(hide yes)
			)
		)
		(property "Value" "GND"
			(at 369.57 67.945 0)
			(effects
				(font
					(size 1.27 1.27)
					(thickness 0.15)
				)
			)
		)
		(property "Footprint" ""
			(at 378.46 71.12 0)
			(effects
				(font
					(size 1.27 1.27)
					(thickness 0.15)
				)
				(justify left bottom)
				(hide yes)
			)
		)
		(property "Datasheet" ""
			(at 378.46 76.2 0)
			(effects
				(font
					(size 1.27 1.27)
					(thickness 0.15)
				)
				(justify left bottom)
				(hide yes)
			)
		)
		(property "Description" ""
			(at 369.57 63.5 0)
			(effects
				(font
					(size 1.27 1.27)
				)
				(hide yes)
			)
		)
		(property "Author" "Antmicro"
			(at 378.46 71.12 0)
			(effects
				(font
					(size 1.27 1.27)
					(thickness 0.15)
				)
				(justify left bottom)
				(hide yes)
			)
		)
		(property "License" "Apache-2.0"
			(at 378.46 73.66 0)
			(effects
				(font
					(size 1.27 1.27)
					(thickness 0.15)
				)
				(justify left bottom)
				(hide yes)
			)
		)
		(pin "1"
		)
		(instances
			(project "usb-c-power-adapter"
				(path ""
					(reference "#PWR029")
					(unit 1)
				)
			)
		)
	)
	(symbol
		(lib_id "antmicropower:+5V")
		(at 391.16 95.25 0)
		(unit 1)
		(exclude_from_sim no)
		(in_bom yes)
		(on_board yes)
		(dnp no)
		(fields_autoplaced yes)
		(property "Reference" "#PWR032"
			(at 406.4 97.79 0)
			(effects
				(font
					(size 1.27 1.27)
					(thickness 0.15)
				)
				(justify left bottom)
				(hide yes)
			)
		)
		(property "Value" "+5V"
			(at 391.16 90.17 0)
			(effects
				(font
					(size 1.27 1.27)
					(thickness 0.15)
				)
			)
		)
		(property "Footprint" ""
			(at 406.4 102.87 0)
			(effects
				(font
					(size 1.27 1.27)
					(thickness 0.15)
				)
				(justify left bottom)
				(hide yes)
			)
		)
		(property "Datasheet" ""
			(at 406.4 105.41 0)
			(effects
				(font
					(size 1.27 1.27)
					(thickness 0.15)
				)
				(justify left bottom)
				(hide yes)
			)
		)
		(property "Description" ""
			(at 391.16 95.25 0)
			(effects
				(font
					(size 1.27 1.27)
				)
				(hide yes)
			)
		)
		(property "Author" "Antmicro"
			(at 406.4 102.87 0)
			(effects
				(font
					(size 1.27 1.27)
					(thickness 0.15)
				)
				(justify left bottom)
				(hide yes)
			)
		)
		(property "License" "Apache-2.0"
			(at 406.4 105.41 0)
			(effects
				(font
					(size 1.27 1.27)
					(thickness 0.15)
				)
				(justify left bottom)
				(hide yes)
			)
		)
		(pin "1"
		)
		(instances
			(project "usb-c-power-adapter"
				(path ""
					(reference "#PWR032")
					(unit 1)
				)
			)
		)
	)
	(symbol
		(lib_id "antmicropower:+12V")
		(at 43.18 167.64 0)
		(unit 1)
		(exclude_from_sim no)
		(in_bom yes)
		(on_board yes)
		(dnp no)
		(fields_autoplaced yes)
		(property "Reference" "#PWR066"
			(at 43.18 171.45 0)
			(effects
				(font
					(size 1.27 1.27)
				)
				(hide yes)
			)
		)
		(property "Value" "+12V"
			(at 43.18 162.56 0)
			(effects
				(font
					(size 1.27 1.27)
				)
			)
		)
		(property "Footprint" ""
			(at 43.18 167.64 0)
			(effects
				(font
					(size 1.27 1.27)
				)
				(hide yes)
			)
		)
		(property "Datasheet" ""
			(at 43.18 167.64 0)
			(effects
				(font
					(size 1.27 1.27)
				)
				(hide yes)
			)
		)
		(property "Description" ""
			(at 43.18 167.64 0)
			(effects
				(font
					(size 1.27 1.27)
				)
				(hide yes)
			)
		)
		(pin "1"
		)
		(instances
			(project "usb-c-power-adapter"
				(path ""
					(reference "#PWR066")
					(unit 1)
				)
			)
		)
	)
	(symbol
		(lib_id "antmicroCapacitorspol:C_Pol_150u_30V_Vishay-T59-EE")
		(at 49.53 76.2 270)
		(unit 1)
		(exclude_from_sim no)
		(in_bom yes)
		(on_board yes)
		(dnp no)
		(fields_autoplaced yes)
		(property "Reference" "C44"
			(at 52.07 76.9366 90)
			(effects
				(font
					(size 1.27 1.27)
					(thickness 0.15)
				)
				(justify left)
			)
		)
		(property "Value" "C_Pol_150u_30V_Vishay-T59-EE"
			(at 39.37 91.44 0)
			(effects
				(font
					(size 1.27 1.27)
					(thickness 0.15)
				)
				(justify left bottom)
				(hide yes)
			)
		)
		(property "Footprint" "antmicro-footprints:C_Pol_Vishay-T59-EE"
			(at 36.83 91.44 0)
			(effects
				(font
					(size 1.27 1.27)
					(thickness 0.15)
				)
				(justify left bottom)
				(hide yes)
			)
		)
		(property "Datasheet" "https://www.vishay.com/docs/40191/t59.pdf"
			(at 34.29 91.44 0)
			(effects
				(font
					(size 1.27 1.27)
					(thickness 0.15)
				)
				(justify left bottom)
				(hide yes)
			)
		)
		(property "Description" "Tantalum Capacitors - Polymer 150uF 30volts 20% 75mohms maxESR"
			(at 49.53 76.2 0)
			(effects
				(font
					(size 1.27 1.27)
				)
				(hide yes)
			)
		)
		(property "MPN" "T59EE157M030C0075"
			(at 36.83 90.17 0)
			(effects
				(font
					(size 1.27 1.27)
				)
				(justify left bottom)
				(hide yes)
			)
		)
		(property "Manufacturer" "Vishay"
			(at 31.75 91.44 0)
			(effects
				(font
					(size 1.27 1.27)
					(thickness 0.15)
				)
				(justify left bottom)
				(hide yes)
			)
		)
		(property "Voltage" "30V"
			(at 29.21 91.44 0)
			(effects
				(font
					(size 1.27 1.27)
					(thickness 0.15)
				)
				(justify left bottom)
				(hide yes)
			)
		)
		(property "Val" "150u"
			(at 52.07 79.4766 90)
			(effects
				(font
					(size 1.27 1.27)
					(thickness 0.15)
				)
				(justify left)
			)
		)
		(property "Author" "Antmicro"
			(at 26.67 91.44 0)
			(effects
				(font
					(size 1.27 1.27)
					(thickness 0.15)
				)
				(justify left bottom)
				(hide yes)
			)
		)
		(property "License" "Apache-2.0"
			(at 24.13 91.44 0)
			(effects
				(font
					(size 1.27 1.27)
					(thickness 0.15)
				)
				(justify left bottom)
				(hide yes)
			)
		)
		(property "Dielectric" "template_dielectric"
			(at 24.13 90.17 0)
			(effects
				(font
					(size 1.27 1.27)
				)
				(justify left bottom)
				(hide yes)
			)
		)
		(pin "2"
		)
		(pin "1"
		)
		(instances
			(project "usb-c-power-adapter"
				(path ""
					(reference "C44")
					(unit 1)
				)
			)
		)
	)
	(symbol
		(lib_id "antmicroResistors0402:R_2k2_0402")
		(at 177.8 175.26 90)
		(unit 1)
		(exclude_from_sim no)
		(in_bom yes)
		(on_board yes)
		(dnp no)
		(fields_autoplaced yes)
		(property "Reference" "R28"
			(at 180.34 171.45 90)
			(effects
				(font
					(size 1.27 1.27)
					(thickness 0.15)
				)
				(justify right)
			)
		)
		(property "Value" "R_2k2_0402"
			(at 190.5 154.94 0)
			(effects
				(font
					(size 1.27 1.27)
					(thickness 0.15)
				)
				(justify left bottom)
				(hide yes)
			)
		)
		(property "Footprint" "antmicro-footprints:R_0402_1005Metric"
			(at 193.04 154.94 0)
			(effects
				(font
					(size 1.27 1.27)
					(thickness 0.15)
				)
				(justify left bottom)
				(hide yes)
			)
		)
		(property "Datasheet" "https://www.bourns.com/docs/product-datasheets/cr.pdf"
			(at 195.58 154.94 0)
			(effects
				(font
					(size 1.27 1.27)
					(thickness 0.15)
				)
				(justify left bottom)
				(hide yes)
			)
		)
		(property "Description" "SMD Chip Resistor, 2.2 kohm, ± 1%, 62.5 mW, 0402 [1005 Metric], Thick Film, General Purpose"
			(at 177.8 175.26 0)
			(effects
				(font
					(size 1.27 1.27)
				)
				(hide yes)
			)
		)
		(property "MPN" "CR0402-FX-2201GLF"
			(at 198.12 154.94 0)
			(effects
				(font
					(size 1.27 1.27)
					(thickness 0.15)
				)
				(justify left bottom)
				(hide yes)
			)
		)
		(property "Manufacturer" "Bourns"
			(at 200.66 154.94 0)
			(effects
				(font
					(size 1.27 1.27)
					(thickness 0.15)
				)
				(justify left bottom)
				(hide yes)
			)
		)
		(property "License" "Apache-2.0"
			(at 203.2 154.94 0)
			(effects
				(font
					(size 1.27 1.27)
					(thickness 0.15)
				)
				(justify left bottom)
				(hide yes)
			)
		)
		(property "Author" "Antmicro"
			(at 205.74 154.94 0)
			(effects
				(font
					(size 1.27 1.27)
					(thickness 0.15)
				)
				(justify left bottom)
				(hide yes)
			)
		)
		(property "Val" "2k2"
			(at 180.34 173.99 90)
			(effects
				(font
					(size 1.27 1.27)
					(thickness 0.15)
				)
				(justify right)
			)
		)
		(property "Tolerance" "1%"
			(at 187.96 154.94 0)
			(effects
				(font
					(size 1.27 1.27)
				)
				(justify left bottom)
				(hide yes)
			)
		)
		(pin "1"
		)
		(pin "2"
		)
		(instances
			(project "usb-c-power-adapter"
				(path ""
					(reference "R28")
					(unit 1)
				)
			)
		)
	)
	(symbol
		(lib_id "antmicroCapacitors0402:C_100n_50V_X8L_0402")
		(at 198.12 80.01 90)
		(unit 1)
		(exclude_from_sim no)
		(in_bom yes)
		(on_board yes)
		(dnp no)
		(fields_autoplaced yes)
		(property "Reference" "C15"
			(at 200.66 76.1936 90)
			(effects
				(font
					(size 1.27 1.27)
					(thickness 0.15)
				)
				(justify right)
			)
		)
		(property "Value" "C_100n_50V_X8L_0402"
			(at 220.98 64.77 0)
			(effects
				(font
					(size 1.27 1.27)
					(thickness 0.15)
				)
				(justify left bottom)
				(hide yes)
			)
		)
		(property "Footprint" "antmicro-footprints:C_0402_1005Metric"
			(at 223.52 64.77 0)
			(effects
				(font
					(size 1.27 1.27)
					(thickness 0.15)
				)
				(justify left bottom)
				(hide yes)
			)
		)
		(property "Datasheet" "https://www.murata.com/products/productdetail?partno=GCM155L8EH104KE07%23"
			(at 226.06 64.77 0)
			(effects
				(font
					(size 1.27 1.27)
					(thickness 0.15)
				)
				(justify left bottom)
				(hide yes)
			)
		)
		(property "Description" "SMD Multilayer Ceramic Capacitor, 100nF, 50V, 0402, ±10%, X8L"
			(at 198.12 80.01 0)
			(effects
				(font
					(size 1.27 1.27)
				)
				(hide yes)
			)
		)
		(property "MPN" "GCM155L8EH104KE07D"
			(at 228.6 64.77 0)
			(effects
				(font
					(size 1.27 1.27)
					(thickness 0.15)
				)
				(justify left bottom)
				(hide yes)
			)
		)
		(property "Val" "100n"
			(at 200.66 78.7336 90)
			(effects
				(font
					(size 1.27 1.27)
					(thickness 0.15)
				)
				(justify right)
			)
		)
		(property "Voltage" "50V"
			(at 208.28 64.77 0)
			(effects
				(font
					(size 1.27 1.27)
					(thickness 0.15)
				)
				(justify left bottom)
				(hide yes)
			)
		)
		(property "Dielectric" "X8L"
			(at 210.82 64.77 0)
			(effects
				(font
					(size 1.27 1.27)
					(thickness 0.15)
				)
				(justify left bottom)
				(hide yes)
			)
		)
		(property "Manufacturer" "Murata"
			(at 213.36 64.77 0)
			(effects
				(font
					(size 1.27 1.27)
					(thickness 0.15)
				)
				(justify left bottom)
				(hide yes)
			)
		)
		(property "License" "Apache-2.0"
			(at 215.9 64.77 0)
			(effects
				(font
					(size 1.27 1.27)
					(thickness 0.15)
				)
				(justify left bottom)
				(hide yes)
			)
		)
		(property "Author" "Antmicro"
			(at 218.44 64.77 0)
			(effects
				(font
					(size 1.27 1.27)
					(thickness 0.15)
				)
				(justify left bottom)
				(hide yes)
			)
		)
		(pin "1"
		)
		(pin "2"
		)
		(instances
			(project "usb-c-power-adapter"
				(path ""
					(reference "C15")
					(unit 1)
				)
			)
		)
	)
	(symbol
		(lib_id "antmicropower:GND")
		(at 55.88 116.84 0)
		(mirror y)
		(unit 1)
		(exclude_from_sim no)
		(in_bom yes)
		(on_board yes)
		(dnp no)
		(fields_autoplaced yes)
		(property "Reference" "#PWR05"
			(at 55.88 116.84 0)
			(effects
				(font
					(size 1.27 1.27)
				)
				(justify left)
				(hide yes)
			)
		)
		(property "Value" "GND"
			(at 55.88 121.92 0)
			(effects
				(font
					(size 1.27 1.27)
				)
			)
		)
		(property "Footprint" ""
			(at 55.88 116.84 0)
			(effects
				(font
					(size 1.27 1.27)
					(thickness 0.15)
				)
				(justify left bottom)
				(hide yes)
			)
		)
		(property "Datasheet" ""
			(at 55.88 116.84 0)
			(effects
				(font
					(size 1.27 1.27)
					(thickness 0.15)
				)
				(justify left bottom)
				(hide yes)
			)
		)
		(property "Description" ""
			(at 55.88 116.84 0)
			(effects
				(font
					(size 1.27 1.27)
				)
				(hide yes)
			)
		)
		(property "Author" "Antmicro"
			(at 46.99 124.46 0)
			(effects
				(font
					(size 1.27 1.27)
					(thickness 0.15)
				)
				(justify left bottom)
				(hide yes)
			)
		)
		(property "License" "Apache-2.0"
			(at 46.99 127 0)
			(effects
				(font
					(size 1.27 1.27)
					(thickness 0.15)
				)
				(justify left bottom)
				(hide yes)
			)
		)
		(pin "1"
		)
		(instances
			(project "usb-c-power-adapter"
				(path ""
					(reference "#PWR05")
					(unit 1)
				)
			)
		)
	)
	(symbol
		(lib_id "antmicroTestPoints:TP_0.75mm_SMD")
		(at 217.17 72.39 90)
		(unit 1)
		(exclude_from_sim no)
		(in_bom no)
		(on_board yes)
		(dnp no)
		(property "Reference" "TP7"
			(at 215.9 66.04 90)
			(effects
				(font
					(size 1.27 1.27)
					(thickness 0.15)
				)
				(justify right)
			)
		)
		(property "Value" "TP_0.75mm_SMD"
			(at 220.98 61.595 0)
			(effects
				(font
					(size 1.27 1.27)
					(thickness 0.15)
				)
				(justify left bottom)
				(hide yes)
			)
		)
		(property "Footprint" "antmicro-footprints:TP_SMD_0.75mm"
			(at 223.52 61.595 0)
			(effects
				(font
					(size 1.27 1.27)
					(thickness 0.15)
				)
				(justify left bottom)
				(hide yes)
			)
		)
		(property "Datasheet" ""
			(at 229.87 54.61 0)
			(effects
				(font
					(size 1.27 1.27)
					(thickness 0.15)
				)
				(justify left bottom)
				(hide yes)
			)
		)
		(property "Description" "SMT test point"
			(at 217.17 72.39 0)
			(effects
				(font
					(size 1.27 1.27)
				)
				(hide yes)
			)
		)
		(property "MPN" ""
			(at 228.6 61.595 0)
			(effects
				(font
					(size 1.27 1.27)
					(thickness 0.15)
				)
				(justify left bottom)
				(hide yes)
			)
		)
		(property "Manufacturer" ""
			(at 223.52 61.595 0)
			(effects
				(font
					(size 1.27 1.27)
					(thickness 0.15)
				)
				(justify left bottom)
				(hide yes)
			)
		)
		(property "Author" "Antmicro"
			(at 226.06 61.595 0)
			(effects
				(font
					(size 1.27 1.27)
					(thickness 0.15)
				)
				(justify left bottom)
				(hide yes)
			)
		)
		(property "License" "Apache-2.0"
			(at 228.6 61.595 0)
			(effects
				(font
					(size 1.27 1.27)
					(thickness 0.15)
				)
				(justify left bottom)
				(hide yes)
			)
		)
		(pin "1"
		)
		(instances
			(project "usb-c-power-adapter"
				(path ""
					(reference "TP7")
					(unit 1)
				)
			)
		)
	)
	(symbol
		(lib_id "antmicroResistors0402:R_10k_0.1%_0402")
		(at 189.23 101.6 90)
		(unit 1)
		(exclude_from_sim no)
		(in_bom yes)
		(on_board yes)
		(dnp no)
		(fields_autoplaced yes)
		(property "Reference" "R18"
			(at 191.77 97.79 90)
			(effects
				(font
					(size 1.27 1.27)
					(thickness 0.15)
				)
				(justify right)
			)
		)
		(property "Value" "R_10k_0.1%_0402"
			(at 201.93 81.28 0)
			(effects
				(font
					(size 1.27 1.27)
					(thickness 0.15)
				)
				(justify left bottom)
				(hide yes)
			)
		)
		(property "Footprint" "antmicro-footprints:R_0402_1005Metric"
			(at 204.47 81.28 0)
			(effects
				(font
					(size 1.27 1.27)
					(thickness 0.15)
				)
				(justify left bottom)
				(hide yes)
			)
		)
		(property "Datasheet" "https://www.mouser.com/datasheet/2/54/CRT-1649066.pdf"
			(at 207.01 81.28 0)
			(effects
				(font
					(size 1.27 1.27)
					(thickness 0.15)
				)
				(justify left bottom)
				(hide yes)
			)
		)
		(property "Description" "SMD Chip Resistor, 10 kohm, ± 0.1%, 62.5 mW, 0402 [1005 Metric], Thin Film, Precision Resistors"
			(at 189.23 101.6 0)
			(effects
				(font
					(size 1.27 1.27)
				)
				(hide yes)
			)
		)
		(property "MPN" "CRT0402-BY-1002GLF "
			(at 191.77 97.79 0)
			(effects
				(font
					(size 1.27 1.27)
					(thickness 0.15)
				)
				(justify left bottom)
				(hide yes)
			)
		)
		(property "Val" "10k"
			(at 191.77 100.33 90)
			(effects
				(font
					(size 1.27 1.27)
					(thickness 0.15)
				)
				(justify right)
			)
		)
		(property "Manufacturer" "Bourns"
			(at 212.09 81.28 0)
			(effects
				(font
					(size 1.27 1.27)
					(thickness 0.15)
				)
				(justify left bottom)
				(hide yes)
			)
		)
		(property "Tolerance" "0.1%"
			(at 191.77 102.87 0)
			(effects
				(font
					(size 1.27 1.27)
					(thickness 0.15)
				)
				(justify left bottom)
				(hide yes)
			)
		)
		(property "License" "Apache-2.0"
			(at 214.63 81.28 0)
			(effects
				(font
					(size 1.27 1.27)
					(thickness 0.15)
				)
				(justify left bottom)
				(hide yes)
			)
		)
		(property "Author" "Antmicro"
			(at 217.17 81.28 0)
			(effects
				(font
					(size 1.27 1.27)
					(thickness 0.15)
				)
				(justify left bottom)
				(hide yes)
			)
		)
		(pin "2"
		)
		(pin "1"
		)
		(instances
			(project "usb-c-power-adapter"
				(path ""
					(reference "R18")
					(unit 1)
				)
			)
		)
	)
	(symbol
		(lib_id "antmicropower:GND")
		(at 144.78 116.84 0)
		(unit 1)
		(exclude_from_sim no)
		(in_bom yes)
		(on_board yes)
		(dnp no)
		(fields_autoplaced yes)
		(property "Reference" "#PWR021"
			(at 144.78 116.84 0)
			(effects
				(font
					(size 1.27 1.27)
				)
				(justify left)
				(hide yes)
			)
		)
		(property "Value" "GND"
			(at 144.78 121.285 0)
			(effects
				(font
					(size 1.27 1.27)
				)
			)
		)
		(property "Footprint" ""
			(at 144.78 116.84 0)
			(effects
				(font
					(size 1.27 1.27)
					(thickness 0.15)
				)
				(justify left bottom)
				(hide yes)
			)
		)
		(property "Datasheet" ""
			(at 144.78 116.84 0)
			(effects
				(font
					(size 1.27 1.27)
					(thickness 0.15)
				)
				(justify left bottom)
				(hide yes)
			)
		)
		(property "Description" ""
			(at 144.78 116.84 0)
			(effects
				(font
					(size 1.27 1.27)
				)
				(hide yes)
			)
		)
		(property "Author" "Antmicro"
			(at 153.67 124.46 0)
			(effects
				(font
					(size 1.27 1.27)
					(thickness 0.15)
				)
				(justify left bottom)
				(hide yes)
			)
		)
		(property "License" "Apache-2.0"
			(at 153.67 127 0)
			(effects
				(font
					(size 1.27 1.27)
					(thickness 0.15)
				)
				(justify left bottom)
				(hide yes)
			)
		)
		(pin "1"
		)
		(instances
			(project "usb-c-power-adapter"
				(path ""
					(reference "#PWR021")
					(unit 1)
				)
			)
		)
	)
	(symbol
		(lib_id "antmicropower:+12V")
		(at 43.18 226.06 0)
		(unit 1)
		(exclude_from_sim no)
		(in_bom yes)
		(on_board yes)
		(dnp no)
		(fields_autoplaced yes)
		(property "Reference" "#PWR036"
			(at 43.18 229.87 0)
			(effects
				(font
					(size 1.27 1.27)
				)
				(hide yes)
			)
		)
		(property "Value" "+12V"
			(at 43.18 220.98 0)
			(effects
				(font
					(size 1.27 1.27)
				)
			)
		)
		(property "Footprint" ""
			(at 43.18 226.06 0)
			(effects
				(font
					(size 1.27 1.27)
				)
				(hide yes)
			)
		)
		(property "Datasheet" ""
			(at 43.18 226.06 0)
			(effects
				(font
					(size 1.27 1.27)
				)
				(hide yes)
			)
		)
		(property "Description" ""
			(at 43.18 226.06 0)
			(effects
				(font
					(size 1.27 1.27)
				)
				(hide yes)
			)
		)
		(pin "1"
		)
		(instances
			(project "usb-c-power-adapter"
				(path ""
					(reference "#PWR036")
					(unit 1)
				)
			)
		)
	)
)
